(kicad_sch
	(version 20250114)
	(generator "eeschema")
	(generator_version "9.0")
	(paper "A3")
	(title_block
		(title "Antmicro Baseboard for Jetson AGX Thor")
		(date "2026-02-17")
		(rev "1.1.0")
		(company "Antmicro Ltd")
		(comment 1 "www.antmicro.com")
	)
	(text "L"
		(exclude_from_sim no)
		(at 74.93 139.065 0)
		(effects
			(font
				(size 1.27 1.27)
			)
			(justify left bottom)
		)
	)
	(text "USB Display port alt mode"
		(exclude_from_sim no)
		(at 188.214 23.368 0)
		(effects
			(font
				(size 2.54 2.54)
				(thickness 0.508)
				(bold yes)
			)
		)
	)
	(text "I_{LIM}(A) = 6800/R_{LIM} = 3.09\n"
		(exclude_from_sim no)
		(at 222.504 54.61 0)
		(effects
			(font
				(size 1.27 1.27)
			)
		)
	)
	(text "4 LANE DP"
		(exclude_from_sim no)
		(at 80.01 139.065 0)
		(effects
			(font
				(size 1.27 1.27)
			)
			(justify left bottom)
		)
	)
	(text "L"
		(exclude_from_sim no)
		(at 74.93 132.715 0)
		(effects
			(font
				(size 1.27 1.27)
			)
			(justify left bottom)
		)
	)
	(text "USB ONLY"
		(exclude_from_sim no)
		(at 80.01 135.89 0)
		(effects
			(font
				(size 1.27 1.27)
			)
			(justify left bottom)
		)
	)
	(text "H"
		(exclude_from_sim no)
		(at 74.93 142.24 0)
		(effects
			(font
				(size 1.27 1.27)
			)
			(justify left bottom)
		)
	)
	(text "USB + 2 LANE DP"
		(exclude_from_sim no)
		(at 80.01 142.24 0)
		(effects
			(font
				(size 1.27 1.27)
			)
			(justify left bottom)
		)
	)
	(text "CTL0"
		(exclude_from_sim no)
		(at 74.422 130.048 0)
		(effects
			(font
				(size 1.27 1.27)
				(thickness 0.254)
				(bold yes)
			)
			(justify left bottom)
		)
	)
	(text "H"
		(exclude_from_sim no)
		(at 68.58 139.065 0)
		(effects
			(font
				(size 1.27 1.27)
			)
			(justify left bottom)
		)
	)
	(text "H"
		(exclude_from_sim no)
		(at 68.58 142.24 0)
		(effects
			(font
				(size 1.27 1.27)
			)
			(justify left bottom)
		)
	)
	(text "H"
		(exclude_from_sim no)
		(at 74.93 135.89 0)
		(effects
			(font
				(size 1.27 1.27)
			)
			(justify left bottom)
		)
	)
	(text "L"
		(exclude_from_sim no)
		(at 68.58 132.715 0)
		(effects
			(font
				(size 1.27 1.27)
			)
			(justify left bottom)
		)
	)
	(text "CTL1"
		(exclude_from_sim no)
		(at 68.072 130.048 0)
		(effects
			(font
				(size 1.27 1.27)
				(thickness 0.254)
				(bold yes)
			)
			(justify left bottom)
		)
	)
	(text "USB PORT 1\n"
		(exclude_from_sim no)
		(at 322.58 109.982 0)
		(effects
			(font
				(size 1.27 1.27)
				(thickness 0.254)
				(bold yes)
			)
		)
	)
	(text "L"
		(exclude_from_sim no)
		(at 68.58 135.89 0)
		(effects
			(font
				(size 1.27 1.27)
			)
			(justify left bottom)
		)
	)
	(text "I2C addr: 0x12"
		(exclude_from_sim no)
		(at 134.62 213.868 0)
		(effects
			(font
				(size 1.27 1.27)
			)
		)
	)
	(text "CONFIGURATION"
		(exclude_from_sim no)
		(at 80.01 130.048 0)
		(effects
			(font
				(size 1.27 1.27)
				(thickness 0.254)
				(bold yes)
			)
			(justify left bottom)
		)
	)
	(text "POWER DOWN"
		(exclude_from_sim no)
		(at 80.01 132.715 0)
		(effects
			(font
				(size 1.27 1.27)
			)
			(justify left bottom)
		)
	)
	(junction
		(at 193.04 196.85)
		(diameter 0)
		(color 0 0 0 0)
	)
	(junction
		(at 190.5 184.15)
		(diameter 0)
		(color 0 0 0 0)
	)
	(junction
		(at 275.59 138.43)
		(diameter 0)
		(color 0 0 0 0)
	)
	(junction
		(at 226.06 168.91)
		(diameter 0)
		(color 0 0 0 0)
	)
	(junction
		(at 143.51 228.6)
		(diameter 0)
		(color 0 0 0 0)
	)
	(junction
		(at 187.96 114.3)
		(diameter 0)
		(color 0 0 0 0)
	)
	(junction
		(at 93.98 102.87)
		(diameter 0)
		(color 0 0 0 0)
	)
	(junction
		(at 273.05 143.51)
		(diameter 0)
		(color 0 0 0 0)
	)
	(junction
		(at 170.18 179.07)
		(diameter 0)
		(color 0 0 0 0)
	)
	(junction
		(at 105.41 209.55)
		(diameter 0)
		(color 0 0 0 0)
	)
	(junction
		(at 172.72 196.85)
		(diameter 0)
		(color 0 0 0 0)
	)
	(junction
		(at 302.26 125.73)
		(diameter 0)
		(color 0 0 0 0)
	)
	(junction
		(at 83.82 102.87)
		(diameter 0)
		(color 0 0 0 0)
	)
	(junction
		(at 252.73 161.29)
		(diameter 0)
		(color 0 0 0 0)
	)
	(junction
		(at 288.29 125.73)
		(diameter 0)
		(color 0 0 0 0)
	)
	(junction
		(at 173.99 189.23)
		(diameter 0)
		(color 0 0 0 0)
	)
	(junction
		(at 294.64 176.53)
		(diameter 0)
		(color 0 0 0 0)
	)
	(junction
		(at 189.23 49.53)
		(diameter 0)
		(color 0 0 0 0)
	)
	(junction
		(at 278.13 135.89)
		(diameter 0)
		(color 0 0 0 0)
	)
	(junction
		(at 261.62 63.5)
		(diameter 0)
		(color 0 0 0 0)
	)
	(junction
		(at 180.34 66.04)
		(diameter 0)
		(color 0 0 0 0)
	)
	(junction
		(at 177.8 91.44)
		(diameter 0)
		(color 0 0 0 0)
	)
	(junction
		(at 193.04 181.61)
		(diameter 0)
		(color 0 0 0 0)
	)
	(junction
		(at 173.99 191.77)
		(diameter 0)
		(color 0 0 0 0)
	)
	(junction
		(at 232.41 73.66)
		(diameter 0)
		(color 0 0 0 0)
	)
	(junction
		(at 276.86 63.5)
		(diameter 0)
		(color 0 0 0 0)
	)
	(junction
		(at 72.39 102.87)
		(diameter 0)
		(color 0 0 0 0)
	)
	(junction
		(at 250.19 158.75)
		(diameter 0)
		(color 0 0 0 0)
	)
	(junction
		(at 170.18 201.93)
		(diameter 0)
		(color 0 0 0 0)
	)
	(junction
		(at 189.23 68.58)
		(diameter 0)
		(color 0 0 0 0)
	)
	(junction
		(at 172.72 184.15)
		(diameter 0)
		(color 0 0 0 0)
	)
	(junction
		(at 245.11 151.13)
		(diameter 0)
		(color 0 0 0 0)
	)
	(junction
		(at 280.67 115.57)
		(diameter 0)
		(color 0 0 0 0)
	)
	(junction
		(at 193.04 186.69)
		(diameter 0)
		(color 0 0 0 0)
	)
	(junction
		(at 193.04 176.53)
		(diameter 0)
		(color 0 0 0 0)
	)
	(junction
		(at 190.5 204.47)
		(diameter 0)
		(color 0 0 0 0)
	)
	(junction
		(at 304.8 123.19)
		(diameter 0)
		(color 0 0 0 0)
	)
	(junction
		(at 285.75 123.19)
		(diameter 0)
		(color 0 0 0 0)
	)
	(junction
		(at 105.41 102.87)
		(diameter 0)
		(color 0 0 0 0)
	)
	(junction
		(at 247.65 153.67)
		(diameter 0)
		(color 0 0 0 0)
	)
	(junction
		(at 168.91 207.01)
		(diameter 0)
		(color 0 0 0 0)
	)
	(junction
		(at 204.47 68.58)
		(diameter 0)
		(color 0 0 0 0)
	)
	(junction
		(at 193.04 201.93)
		(diameter 0)
		(color 0 0 0 0)
	)
	(junction
		(at 190.5 209.55)
		(diameter 0)
		(color 0 0 0 0)
	)
	(junction
		(at 283.21 118.11)
		(diameter 0)
		(color 0 0 0 0)
	)
	(junction
		(at 287.02 166.37)
		(diameter 0)
		(color 0 0 0 0)
	)
	(junction
		(at 190.5 199.39)
		(diameter 0)
		(color 0 0 0 0)
	)
	(junction
		(at 97.79 209.55)
		(diameter 0)
		(color 0 0 0 0)
	)
	(junction
		(at 193.04 191.77)
		(diameter 0)
		(color 0 0 0 0)
	)
	(junction
		(at 119.38 138.43)
		(diameter 0)
		(color 0 0 0 0)
	)
	(junction
		(at 190.5 194.31)
		(diameter 0)
		(color 0 0 0 0)
	)
	(junction
		(at 198.12 49.53)
		(diameter 0)
		(color 0 0 0 0)
	)
	(junction
		(at 228.6 166.37)
		(diameter 0)
		(color 0 0 0 0)
	)
	(junction
		(at 259.08 63.5)
		(diameter 0)
		(color 0 0 0 0)
	)
	(junction
		(at 116.84 140.97)
		(diameter 0)
		(color 0 0 0 0)
	)
	(junction
		(at 288.29 176.53)
		(diameter 0)
		(color 0 0 0 0)
	)
	(junction
		(at 270.51 146.05)
		(diameter 0)
		(color 0 0 0 0)
	)
	(junction
		(at 306.07 110.49)
		(diameter 0)
		(color 0 0 0 0)
	)
	(junction
		(at 287.02 63.5)
		(diameter 0)
		(color 0 0 0 0)
	)
	(junction
		(at 190.5 189.23)
		(diameter 0)
		(color 0 0 0 0)
	)
	(junction
		(at 116.84 228.6)
		(diameter 0)
		(color 0 0 0 0)
	)
	(junction
		(at 187.96 91.44)
		(diameter 0)
		(color 0 0 0 0)
	)
	(junction
		(at 115.57 102.87)
		(diameter 0)
		(color 0 0 0 0)
	)
	(junction
		(at 297.18 63.5)
		(diameter 0)
		(color 0 0 0 0)
	)
	(junction
		(at 289.56 168.91)
		(diameter 0)
		(color 0 0 0 0)
	)
	(no_connect
		(at 233.68 125.73)
	)
	(no_connect
		(at 220.98 172.72)
	)
	(no_connect
		(at 223.52 172.72)
	)
	(no_connect
		(at 201.93 125.73)
	)
	(no_connect
		(at 233.68 123.19)
	)
	(bus_entry
		(at 74.93 152.4)
		(size 1.27 1.27)
		(stroke
			(width 0)
			(type default)
		)
	)
	(bus_entry
		(at 109.22 198.12)
		(size 1.27 1.27)
		(stroke
			(width 0)
			(type default)
		)
	)
	(bus_entry
		(at 74.93 157.48)
		(size 1.27 1.27)
		(stroke
			(width 0)
			(type default)
		)
	)
	(bus_entry
		(at 67.31 118.11)
		(size 1.27 1.27)
		(stroke
			(width 0)
			(type default)
		)
	)
	(bus_entry
		(at 109.22 185.42)
		(size 1.27 1.27)
		(stroke
			(width 0)
			(type default)
		)
	)
	(bus_entry
		(at 181.61 227.33)
		(size -1.27 1.27)
		(stroke
			(width 0)
			(type default)
		)
	)
	(bus_entry
		(at 109.22 165.1)
		(size 1.27 1.27)
		(stroke
			(width 0)
			(type default)
		)
	)
	(bus_entry
		(at 109.22 193.04)
		(size 1.27 1.27)
		(stroke
			(width 0)
			(type default)
		)
	)
	(bus_entry
		(at 109.22 175.26)
		(size 1.27 1.27)
		(stroke
			(width 0)
			(type default)
		)
	)
	(bus_entry
		(at 267.97 124.46)
		(size 1.27 1.27)
		(stroke
			(width 0)
			(type default)
		)
	)
	(bus_entry
		(at 109.22 167.64)
		(size 1.27 1.27)
		(stroke
			(width 0)
			(type default)
		)
	)
	(bus_entry
		(at 109.22 177.8)
		(size 1.27 1.27)
		(stroke
			(width 0)
			(type default)
		)
	)
	(bus_entry
		(at 109.22 182.88)
		(size 1.27 1.27)
		(stroke
			(width 0)
			(type default)
		)
	)
	(bus_entry
		(at 74.93 149.86)
		(size 1.27 1.27)
		(stroke
			(width 0)
			(type default)
		)
	)
	(bus_entry
		(at 109.22 190.5)
		(size 1.27 1.27)
		(stroke
			(width 0)
			(type default)
		)
	)
	(bus_entry
		(at 109.22 200.66)
		(size 1.27 1.27)
		(stroke
			(width 0)
			(type default)
		)
	)
	(bus_entry
		(at 67.31 120.65)
		(size 1.27 1.27)
		(stroke
			(width 0)
			(type default)
		)
	)
	(bus_entry
		(at 267.97 121.92)
		(size 1.27 1.27)
		(stroke
			(width 0)
			(type default)
		)
	)
	(bus_entry
		(at 74.93 160.02)
		(size 1.27 1.27)
		(stroke
			(width 0)
			(type default)
		)
	)
	(wire
		(pts
			(xy 92.71 158.75) (xy 96.52 158.75)
		)
		(stroke
			(width 0)
			(type default)
		)
	)
	(wire
		(pts
			(xy 97.79 215.9) (xy 97.79 217.17)
		)
		(stroke
			(width 0)
			(type default)
		)
	)
	(wire
		(pts
			(xy 275.59 138.43) (xy 306.07 138.43)
		)
		(stroke
			(width 0)
			(type default)
		)
	)
	(wire
		(pts
			(xy 110.49 168.91) (xy 125.73 168.91)
		)
		(stroke
			(width 0)
			(type default)
		)
	)
	(bus
		(pts
			(xy 109.22 165.1) (xy 109.22 167.64)
		)
		(stroke
			(width 0)
			(type default)
		)
	)
	(wire
		(pts
			(xy 104.14 153.67) (xy 125.73 153.67)
		)
		(stroke
			(width 0)
			(type default)
		)
	)
	(wire
		(pts
			(xy 114.3 138.43) (xy 119.38 138.43)
		)
		(stroke
			(width 0)
			(type default)
		)
	)
	(wire
		(pts
			(xy 187.96 113.03) (xy 187.96 114.3)
		)
		(stroke
			(width 0)
			(type default)
		)
	)
	(wire
		(pts
			(xy 72.39 109.22) (xy 72.39 110.49)
		)
		(stroke
			(width 0)
			(type default)
		)
	)
	(wire
		(pts
			(xy 68.58 121.92) (xy 116.84 121.92)
		)
		(stroke
			(width 0)
			(type default)
		)
	)
	(wire
		(pts
			(xy 288.29 97.79) (xy 288.29 125.73)
		)
		(stroke
			(width 0)
			(type default)
		)
	)
	(wire
		(pts
			(xy 168.91 209.55) (xy 168.91 207.01)
		)
		(stroke
			(width 0)
			(type default)
		)
	)
	(wire
		(pts
			(xy 135.89 237.49) (xy 135.89 228.6)
		)
		(stroke
			(width 0)
			(type default)
		)
	)
	(wire
		(pts
			(xy 297.18 63.5) (xy 306.07 63.5)
		)
		(stroke
			(width 0)
			(type default)
		)
	)
	(wire
		(pts
			(xy 187.96 91.44) (xy 187.96 95.25)
		)
		(stroke
			(width 0)
			(type default)
		)
	)
	(wire
		(pts
			(xy 190.5 189.23) (xy 190.5 194.31)
		)
		(stroke
			(width 0)
			(type default)
		)
	)
	(wire
		(pts
			(xy 143.51 228.6) (xy 143.51 229.87)
		)
		(stroke
			(width 0)
			(type default)
		)
	)
	(wire
		(pts
			(xy 278.13 135.89) (xy 278.13 172.72)
		)
		(stroke
			(width 0)
			(type default)
		)
	)
	(wire
		(pts
			(xy 228.6 166.37) (xy 287.02 166.37)
		)
		(stroke
			(width 0)
			(type default)
		)
	)
	(wire
		(pts
			(xy 76.2 158.75) (xy 90.17 158.75)
		)
		(stroke
			(width 0)
			(type default)
		)
	)
	(polyline
		(pts
			(xy 73.66 127) (xy 73.66 143.51)
		)
		(stroke
			(width 0)
			(type solid)
		)
	)
	(wire
		(pts
			(xy 198.12 49.53) (xy 189.23 49.53)
		)
		(stroke
			(width 0)
			(type default)
		)
	)
	(wire
		(pts
			(xy 275.59 138.43) (xy 275.59 172.72)
		)
		(stroke
			(width 0)
			(type default)
		)
	)
	(wire
		(pts
			(xy 199.39 68.58) (xy 204.47 68.58)
		)
		(stroke
			(width 0)
			(type default)
		)
	)
	(wire
		(pts
			(xy 110.49 179.07) (xy 125.73 179.07)
		)
		(stroke
			(width 0)
			(type default)
		)
	)
	(wire
		(pts
			(xy 116.84 140.97) (xy 125.73 140.97)
		)
		(stroke
			(width 0)
			(type default)
		)
	)
	(polyline
		(pts
			(xy 67.31 130.81) (xy 99.06 130.81)
		)
		(stroke
			(width 0)
			(type solid)
		)
	)
	(wire
		(pts
			(xy 170.18 184.15) (xy 170.18 179.07)
		)
		(stroke
			(width 0)
			(type default)
		)
	)
	(wire
		(pts
			(xy 184.15 207.01) (xy 193.04 207.01)
		)
		(stroke
			(width 0)
			(type default)
		)
	)
	(wire
		(pts
			(xy 261.62 173.99) (xy 261.62 171.45)
		)
		(stroke
			(width 0)
			(type default)
		)
	)
	(wire
		(pts
			(xy 190.5 204.47) (xy 190.5 209.55)
		)
		(stroke
			(width 0)
			(type default)
		)
	)
	(wire
		(pts
			(xy 105.41 109.22) (xy 105.41 110.49)
		)
		(stroke
			(width 0)
			(type default)
		)
	)
	(wire
		(pts
			(xy 302.26 130.81) (xy 302.26 125.73)
		)
		(stroke
			(width 0)
			(type default)
		)
	)
	(bus
		(pts
			(xy 109.22 185.42) (xy 109.22 190.5)
		)
		(stroke
			(width 0)
			(type default)
		)
	)
	(wire
		(pts
			(xy 205.74 63.5) (xy 208.28 63.5)
		)
		(stroke
			(width 0)
			(type default)
		)
	)
	(wire
		(pts
			(xy 194.31 68.58) (xy 189.23 68.58)
		)
		(stroke
			(width 0)
			(type default)
		)
	)
	(wire
		(pts
			(xy 151.13 189.23) (xy 173.99 189.23)
		)
		(stroke
			(width 0)
			(type default)
		)
	)
	(wire
		(pts
			(xy 119.38 132.08) (xy 119.38 138.43)
		)
		(stroke
			(width 0)
			(type default)
		)
	)
	(wire
		(pts
			(xy 269.24 125.73) (xy 288.29 125.73)
		)
		(stroke
			(width 0)
			(type default)
		)
	)
	(wire
		(pts
			(xy 151.13 158.75) (xy 172.72 158.75)
		)
		(stroke
			(width 0)
			(type default)
		)
	)
	(wire
		(pts
			(xy 184.15 209.55) (xy 190.5 209.55)
		)
		(stroke
			(width 0)
			(type default)
		)
	)
	(wire
		(pts
			(xy 119.38 119.38) (xy 119.38 127)
		)
		(stroke
			(width 0)
			(type default)
		)
	)
	(bus
		(pts
			(xy 109.22 182.88) (xy 109.22 185.42)
		)
		(stroke
			(width 0)
			(type default)
		)
	)
	(wire
		(pts
			(xy 115.57 109.22) (xy 115.57 110.49)
		)
		(stroke
			(width 0)
			(type default)
		)
	)
	(wire
		(pts
			(xy 173.99 186.69) (xy 179.07 186.69)
		)
		(stroke
			(width 0)
			(type default)
		)
	)
	(bus
		(pts
			(xy 181.61 227.33) (xy 182.88 226.06)
		)
		(stroke
			(width 0)
			(type default)
		)
	)
	(wire
		(pts
			(xy 184.15 196.85) (xy 193.04 196.85)
		)
		(stroke
			(width 0)
			(type default)
		)
	)
	(wire
		(pts
			(xy 172.72 181.61) (xy 179.07 181.61)
		)
		(stroke
			(width 0)
			(type default)
		)
	)
	(wire
		(pts
			(xy 283.21 97.79) (xy 283.21 118.11)
		)
		(stroke
			(width 0)
			(type default)
		)
	)
	(wire
		(pts
			(xy 294.64 173.99) (xy 306.07 173.99)
		)
		(stroke
			(width 0)
			(type default)
		)
	)
	(wire
		(pts
			(xy 177.8 143.51) (xy 273.05 143.51)
		)
		(stroke
			(width 0)
			(type default)
		)
	)
	(wire
		(pts
			(xy 143.51 227.33) (xy 143.51 228.6)
		)
		(stroke
			(width 0)
			(type default)
		)
	)
	(wire
		(pts
			(xy 287.02 175.26) (xy 287.02 176.53)
		)
		(stroke
			(width 0)
			(type default)
		)
	)
	(bus
		(pts
			(xy 109.22 190.5) (xy 109.22 193.04)
		)
		(stroke
			(width 0)
			(type default)
		)
	)
	(wire
		(pts
			(xy 125.73 102.87) (xy 125.73 135.89)
		)
		(stroke
			(width 0)
			(type default)
		)
	)
	(wire
		(pts
			(xy 205.74 49.53) (xy 198.12 49.53)
		)
		(stroke
			(width 0)
			(type default)
		)
	)
	(wire
		(pts
			(xy 204.47 74.93) (xy 204.47 76.2)
		)
		(stroke
			(width 0)
			(type default)
		)
	)
	(bus
		(pts
			(xy 264.16 120.65) (xy 266.7 120.65)
		)
		(stroke
			(width 0)
			(type default)
		)
	)
	(wire
		(pts
			(xy 172.72 184.15) (xy 179.07 184.15)
		)
		(stroke
			(width 0)
			(type default)
		)
	)
	(wire
		(pts
			(xy 105.41 237.49) (xy 105.41 209.55)
		)
		(stroke
			(width 0)
			(type default)
		)
	)
	(wire
		(pts
			(xy 259.08 63.5) (xy 261.62 63.5)
		)
		(stroke
			(width 0)
			(type default)
		)
	)
	(bus
		(pts
			(xy 109.22 193.04) (xy 109.22 198.12)
		)
		(stroke
			(width 0)
			(type default)
		)
	)
	(wire
		(pts
			(xy 83.82 102.87) (xy 83.82 104.14)
		)
		(stroke
			(width 0)
			(type default)
		)
	)
	(wire
		(pts
			(xy 261.62 63.5) (xy 276.86 63.5)
		)
		(stroke
			(width 0)
			(type default)
		)
	)
	(wire
		(pts
			(xy 190.5 194.31) (xy 190.5 199.39)
		)
		(stroke
			(width 0)
			(type default)
		)
	)
	(wire
		(pts
			(xy 104.14 161.29) (xy 125.73 161.29)
		)
		(stroke
			(width 0)
			(type default)
		)
	)
	(wire
		(pts
			(xy 204.47 68.58) (xy 208.28 68.58)
		)
		(stroke
			(width 0)
			(type default)
		)
	)
	(wire
		(pts
			(xy 287.02 69.85) (xy 287.02 71.12)
		)
		(stroke
			(width 0)
			(type default)
		)
	)
	(wire
		(pts
			(xy 90.17 193.04) (xy 90.17 194.31)
		)
		(stroke
			(width 0)
			(type default)
		)
	)
	(wire
		(pts
			(xy 68.58 119.38) (xy 119.38 119.38)
		)
		(stroke
			(width 0)
			(type default)
		)
	)
	(wire
		(pts
			(xy 187.96 114.3) (xy 201.93 114.3)
		)
		(stroke
			(width 0)
			(type default)
		)
	)
	(bus
		(pts
			(xy 67.31 118.11) (xy 66.04 116.84)
		)
		(stroke
			(width 0)
			(type default)
		)
	)
	(wire
		(pts
			(xy 247.65 153.67) (xy 247.65 172.72)
		)
		(stroke
			(width 0)
			(type default)
		)
	)
	(wire
		(pts
			(xy 110.49 191.77) (xy 125.73 191.77)
		)
		(stroke
			(width 0)
			(type default)
		)
	)
	(wire
		(pts
			(xy 285.75 97.79) (xy 285.75 123.19)
		)
		(stroke
			(width 0)
			(type default)
		)
	)
	(wire
		(pts
			(xy 205.74 49.53) (xy 205.74 63.5)
		)
		(stroke
			(width 0)
			(type default)
		)
	)
	(wire
		(pts
			(xy 212.09 171.45) (xy 218.44 171.45)
		)
		(stroke
			(width 0)
			(type default)
		)
	)
	(wire
		(pts
			(xy 233.68 118.11) (xy 283.21 118.11)
		)
		(stroke
			(width 0)
			(type default)
		)
	)
	(wire
		(pts
			(xy 90.17 158.75) (xy 92.71 161.29)
		)
		(stroke
			(width 0)
			(type default)
		)
	)
	(wire
		(pts
			(xy 276.86 63.5) (xy 287.02 63.5)
		)
		(stroke
			(width 0)
			(type default)
		)
	)
	(wire
		(pts
			(xy 276.86 63.5) (xy 276.86 64.77)
		)
		(stroke
			(width 0)
			(type default)
		)
	)
	(wire
		(pts
			(xy 177.8 100.33) (xy 177.8 101.6)
		)
		(stroke
			(width 0)
			(type default)
		)
	)
	(wire
		(pts
			(xy 168.91 207.01) (xy 179.07 207.01)
		)
		(stroke
			(width 0)
			(type default)
		)
	)
	(wire
		(pts
			(xy 151.13 209.55) (xy 152.4 209.55)
		)
		(stroke
			(width 0)
			(type default)
		)
	)
	(polyline
		(pts
			(xy 67.31 127) (xy 67.31 143.51)
		)
		(stroke
			(width 0)
			(type solid)
		)
	)
	(wire
		(pts
			(xy 289.56 168.91) (xy 306.07 168.91)
		)
		(stroke
			(width 0)
			(type default)
		)
	)
	(wire
		(pts
			(xy 168.91 209.55) (xy 179.07 209.55)
		)
		(stroke
			(width 0)
			(type default)
		)
	)
	(polyline
		(pts
			(xy 80.01 127) (xy 80.01 143.51)
		)
		(stroke
			(width 0)
			(type solid)
		)
	)
	(wire
		(pts
			(xy 116.84 228.6) (xy 135.89 228.6)
		)
		(stroke
			(width 0)
			(type default)
		)
	)
	(wire
		(pts
			(xy 119.38 138.43) (xy 125.73 138.43)
		)
		(stroke
			(width 0)
			(type default)
		)
	)
	(polyline
		(pts
			(xy 99.06 143.51) (xy 67.31 143.51)
		)
		(stroke
			(width 0)
			(type solid)
		)
	)
	(wire
		(pts
			(xy 151.13 153.67) (xy 247.65 153.67)
		)
		(stroke
			(width 0)
			(type default)
		)
	)
	(wire
		(pts
			(xy 287.02 63.5) (xy 297.18 63.5)
		)
		(stroke
			(width 0)
			(type default)
		)
	)
	(wire
		(pts
			(xy 250.19 158.75) (xy 306.07 158.75)
		)
		(stroke
			(width 0)
			(type default)
		)
	)
	(wire
		(pts
			(xy 198.12 110.49) (xy 201.93 110.49)
		)
		(stroke
			(width 0)
			(type default)
		)
	)
	(wire
		(pts
			(xy 114.3 140.97) (xy 116.84 140.97)
		)
		(stroke
			(width 0)
			(type default)
		)
	)
	(wire
		(pts
			(xy 187.96 100.33) (xy 187.96 101.6)
		)
		(stroke
			(width 0)
			(type default)
		)
	)
	(wire
		(pts
			(xy 143.51 220.98) (xy 143.51 222.25)
		)
		(stroke
			(width 0)
			(type default)
		)
	)
	(wire
		(pts
			(xy 105.41 102.87) (xy 115.57 102.87)
		)
		(stroke
			(width 0)
			(type default)
		)
	)
	(wire
		(pts
			(xy 151.13 135.89) (xy 278.13 135.89)
		)
		(stroke
			(width 0)
			(type default)
		)
	)
	(wire
		(pts
			(xy 189.23 48.26) (xy 189.23 49.53)
		)
		(stroke
			(width 0)
			(type default)
		)
	)
	(polyline
		(pts
			(xy 67.31 137.16) (xy 99.06 137.16)
		)
		(stroke
			(width 0)
			(type solid)
		)
	)
	(wire
		(pts
			(xy 116.84 227.33) (xy 116.84 228.6)
		)
		(stroke
			(width 0)
			(type default)
		)
	)
	(wire
		(pts
			(xy 267.97 171.45) (xy 267.97 172.72)
		)
		(stroke
			(width 0)
			(type default)
		)
	)
	(wire
		(pts
			(xy 170.18 179.07) (xy 170.18 176.53)
		)
		(stroke
			(width 0)
			(type default)
		)
	)
	(wire
		(pts
			(xy 76.2 182.88) (xy 90.17 182.88)
		)
		(stroke
			(width 0)
			(type default)
		)
	)
	(wire
		(pts
			(xy 287.02 166.37) (xy 306.07 166.37)
		)
		(stroke
			(width 0)
			(type default)
		)
	)
	(wire
		(pts
			(xy 236.22 173.99) (xy 236.22 171.45)
		)
		(stroke
			(width 0)
			(type default)
		)
	)
	(polyline
		(pts
			(xy 67.31 127) (xy 99.06 127)
		)
		(stroke
			(width 0)
			(type solid)
		)
	)
	(wire
		(pts
			(xy 294.64 179.07) (xy 294.64 176.53)
		)
		(stroke
			(width 0)
			(type default)
		)
	)
	(wire
		(pts
			(xy 170.18 196.85) (xy 170.18 201.93)
		)
		(stroke
			(width 0)
			(type default)
		)
	)
	(wire
		(pts
			(xy 184.15 204.47) (xy 190.5 204.47)
		)
		(stroke
			(width 0)
			(type default)
		)
	)
	(wire
		(pts
			(xy 187.96 91.44) (xy 198.12 91.44)
		)
		(stroke
			(width 0)
			(type default)
		)
	)
	(wire
		(pts
			(xy 184.15 194.31) (xy 190.5 194.31)
		)
		(stroke
			(width 0)
			(type default)
		)
	)
	(wire
		(pts
			(xy 170.18 201.93) (xy 170.18 204.47)
		)
		(stroke
			(width 0)
			(type default)
		)
	)
	(wire
		(pts
			(xy 223.52 63.5) (xy 259.08 63.5)
		)
		(stroke
			(width 0)
			(type default)
		)
	)
	(wire
		(pts
			(xy 90.17 185.42) (xy 90.17 187.96)
		)
		(stroke
			(width 0)
			(type default)
		)
	)
	(wire
		(pts
			(xy 173.99 191.77) (xy 179.07 191.77)
		)
		(stroke
			(width 0)
			(type default)
		)
	)
	(wire
		(pts
			(xy 184.15 186.69) (xy 193.04 186.69)
		)
		(stroke
			(width 0)
			(type default)
		)
	)
	(polyline
		(pts
			(xy 67.31 133.35) (xy 99.06 133.35)
		)
		(stroke
			(width 0)
			(type solid)
		)
	)
	(wire
		(pts
			(xy 181.61 146.05) (xy 270.51 146.05)
		)
		(stroke
			(width 0)
			(type default)
		)
	)
	(wire
		(pts
			(xy 168.91 207.01) (xy 168.91 199.39)
		)
		(stroke
			(width 0)
			(type default)
		)
	)
	(wire
		(pts
			(xy 101.6 158.75) (xy 125.73 158.75)
		)
		(stroke
			(width 0)
			(type default)
		)
	)
	(wire
		(pts
			(xy 193.04 186.69) (xy 193.04 191.77)
		)
		(stroke
			(width 0)
			(type default)
		)
	)
	(bus
		(pts
			(xy 74.93 157.48) (xy 74.93 160.02)
		)
		(stroke
			(width 0)
			(type default)
		)
	)
	(wire
		(pts
			(xy 115.57 102.87) (xy 125.73 102.87)
		)
		(stroke
			(width 0)
			(type default)
		)
	)
	(wire
		(pts
			(xy 232.41 66.04) (xy 232.41 67.31)
		)
		(stroke
			(width 0)
			(type default)
		)
	)
	(wire
		(pts
			(xy 190.5 179.07) (xy 190.5 184.15)
		)
		(stroke
			(width 0)
			(type default)
		)
	)
	(wire
		(pts
			(xy 184.15 181.61) (xy 193.04 181.61)
		)
		(stroke
			(width 0)
			(type default)
		)
	)
	(wire
		(pts
			(xy 184.15 189.23) (xy 190.5 189.23)
		)
		(stroke
			(width 0)
			(type default)
		)
	)
	(wire
		(pts
			(xy 110.49 184.15) (xy 125.73 184.15)
		)
		(stroke
			(width 0)
			(type default)
		)
	)
	(wire
		(pts
			(xy 187.96 114.3) (xy 187.96 115.57)
		)
		(stroke
			(width 0)
			(type default)
		)
	)
	(wire
		(pts
			(xy 116.84 132.08) (xy 116.84 140.97)
		)
		(stroke
			(width 0)
			(type default)
		)
	)
	(wire
		(pts
			(xy 110.49 237.49) (xy 105.41 237.49)
		)
		(stroke
			(width 0)
			(type default)
		)
	)
	(wire
		(pts
			(xy 172.72 194.31) (xy 172.72 196.85)
		)
		(stroke
			(width 0)
			(type default)
		)
	)
	(wire
		(pts
			(xy 270.51 146.05) (xy 306.07 146.05)
		)
		(stroke
			(width 0)
			(type default)
		)
	)
	(wire
		(pts
			(xy 297.18 69.85) (xy 297.18 71.12)
		)
		(stroke
			(width 0)
			(type default)
		)
	)
	(wire
		(pts
			(xy 83.82 109.22) (xy 83.82 110.49)
		)
		(stroke
			(width 0)
			(type default)
		)
	)
	(wire
		(pts
			(xy 198.12 49.53) (xy 198.12 50.8)
		)
		(stroke
			(width 0)
			(type default)
		)
	)
	(wire
		(pts
			(xy 198.12 55.88) (xy 198.12 57.15)
		)
		(stroke
			(width 0)
			(type default)
		)
	)
	(wire
		(pts
			(xy 116.84 121.92) (xy 116.84 127)
		)
		(stroke
			(width 0)
			(type default)
		)
	)
	(wire
		(pts
			(xy 172.72 196.85) (xy 179.07 196.85)
		)
		(stroke
			(width 0)
			(type default)
		)
	)
	(wire
		(pts
			(xy 193.04 175.26) (xy 193.04 176.53)
		)
		(stroke
			(width 0)
			(type default)
		)
	)
	(wire
		(pts
			(xy 193.04 191.77) (xy 193.04 196.85)
		)
		(stroke
			(width 0)
			(type default)
		)
	)
	(wire
		(pts
			(xy 218.44 171.45) (xy 218.44 172.72)
		)
		(stroke
			(width 0)
			(type default)
		)
	)
	(bus
		(pts
			(xy 67.31 118.11) (xy 67.31 120.65)
		)
		(stroke
			(width 0)
			(type default)
		)
	)
	(wire
		(pts
			(xy 170.18 201.93) (xy 179.07 201.93)
		)
		(stroke
			(width 0)
			(type default)
		)
	)
	(wire
		(pts
			(xy 252.73 161.29) (xy 252.73 172.72)
		)
		(stroke
			(width 0)
			(type default)
		)
	)
	(wire
		(pts
			(xy 151.13 143.51) (xy 172.72 143.51)
		)
		(stroke
			(width 0)
			(type default)
		)
	)
	(wire
		(pts
			(xy 190.5 184.15) (xy 190.5 189.23)
		)
		(stroke
			(width 0)
			(type default)
		)
	)
	(wire
		(pts
			(xy 184.15 179.07) (xy 190.5 179.07)
		)
		(stroke
			(width 0)
			(type default)
		)
	)
	(wire
		(pts
			(xy 177.8 66.04) (xy 180.34 66.04)
		)
		(stroke
			(width 0)
			(type default)
		)
	)
	(bus
		(pts
			(xy 109.22 177.8) (xy 109.22 182.88)
		)
		(stroke
			(width 0)
			(type default)
		)
	)
	(wire
		(pts
			(xy 306.07 130.81) (xy 302.26 130.81)
		)
		(stroke
			(width 0)
			(type default)
		)
	)
	(bus
		(pts
			(xy 109.22 167.64) (xy 109.22 175.26)
		)
		(stroke
			(width 0)
			(type default)
		)
	)
	(wire
		(pts
			(xy 304.8 128.27) (xy 306.07 128.27)
		)
		(stroke
			(width 0)
			(type default)
		)
	)
	(wire
		(pts
			(xy 93.98 109.22) (xy 93.98 110.49)
		)
		(stroke
			(width 0)
			(type default)
		)
	)
	(wire
		(pts
			(xy 294.64 176.53) (xy 294.64 173.99)
		)
		(stroke
			(width 0)
			(type default)
		)
	)
	(wire
		(pts
			(xy 306.07 63.5) (xy 306.07 110.49)
		)
		(stroke
			(width 0)
			(type default)
		)
	)
	(wire
		(pts
			(xy 93.98 102.87) (xy 105.41 102.87)
		)
		(stroke
			(width 0)
			(type default)
		)
	)
	(wire
		(pts
			(xy 121.92 207.01) (xy 125.73 207.01)
		)
		(stroke
			(width 0)
			(type default)
		)
	)
	(wire
		(pts
			(xy 252.73 161.29) (xy 306.07 161.29)
		)
		(stroke
			(width 0)
			(type default)
		)
	)
	(wire
		(pts
			(xy 233.68 115.57) (xy 280.67 115.57)
		)
		(stroke
			(width 0)
			(type default)
		)
	)
	(wire
		(pts
			(xy 223.52 66.04) (xy 232.41 66.04)
		)
		(stroke
			(width 0)
			(type default)
		)
	)
	(wire
		(pts
			(xy 97.79 209.55) (xy 105.41 209.55)
		)
		(stroke
			(width 0)
			(type default)
		)
	)
	(wire
		(pts
			(xy 151.13 191.77) (xy 173.99 191.77)
		)
		(stroke
			(width 0)
			(type default)
		)
	)
	(wire
		(pts
			(xy 151.13 196.85) (xy 170.18 196.85)
		)
		(stroke
			(width 0)
			(type default)
		)
	)
	(wire
		(pts
			(xy 177.8 158.75) (xy 250.19 158.75)
		)
		(stroke
			(width 0)
			(type default)
		)
	)
	(wire
		(pts
			(xy 232.41 74.93) (xy 232.41 73.66)
		)
		(stroke
			(width 0)
			(type default)
		)
	)
	(wire
		(pts
			(xy 270.51 146.05) (xy 270.51 172.72)
		)
		(stroke
			(width 0)
			(type default)
		)
	)
	(wire
		(pts
			(xy 276.86 69.85) (xy 276.86 71.12)
		)
		(stroke
			(width 0)
			(type default)
		)
	)
	(wire
		(pts
			(xy 280.67 115.57) (xy 306.07 115.57)
		)
		(stroke
			(width 0)
			(type default)
		)
	)
	(wire
		(pts
			(xy 173.99 194.31) (xy 179.07 194.31)
		)
		(stroke
			(width 0)
			(type default)
		)
	)
	(wire
		(pts
			(xy 76.2 153.67) (xy 99.06 153.67)
		)
		(stroke
			(width 0)
			(type default)
		)
	)
	(wire
		(pts
			(xy 172.72 186.69) (xy 172.72 184.15)
		)
		(stroke
			(width 0)
			(type default)
		)
	)
	(wire
		(pts
			(xy 72.39 102.87) (xy 83.82 102.87)
		)
		(stroke
			(width 0)
			(type default)
		)
	)
	(wire
		(pts
			(xy 261.62 63.5) (xy 261.62 64.77)
		)
		(stroke
			(width 0)
			(type default)
		)
	)
	(wire
		(pts
			(xy 114.3 143.51) (xy 125.73 143.51)
		)
		(stroke
			(width 0)
			(type default)
		)
	)
	(wire
		(pts
			(xy 151.13 138.43) (xy 275.59 138.43)
		)
		(stroke
			(width 0)
			(type default)
		)
	)
	(wire
		(pts
			(xy 287.02 176.53) (xy 288.29 176.53)
		)
		(stroke
			(width 0)
			(type default)
		)
	)
	(bus
		(pts
			(xy 185.42 226.06) (xy 182.88 226.06)
		)
		(stroke
			(width 0)
			(type default)
		)
	)
	(wire
		(pts
			(xy 172.72 184.15) (xy 172.72 181.61)
		)
		(stroke
			(width 0)
			(type default)
		)
	)
	(wire
		(pts
			(xy 190.5 199.39) (xy 190.5 204.47)
		)
		(stroke
			(width 0)
			(type default)
		)
	)
	(wire
		(pts
			(xy 288.29 176.53) (xy 289.56 176.53)
		)
		(stroke
			(width 0)
			(type default)
		)
	)
	(wire
		(pts
			(xy 278.13 97.79) (xy 278.13 99.06)
		)
		(stroke
			(width 0)
			(type default)
		)
	)
	(wire
		(pts
			(xy 105.41 209.55) (xy 125.73 209.55)
		)
		(stroke
			(width 0)
			(type default)
		)
	)
	(wire
		(pts
			(xy 173.99 189.23) (xy 179.07 189.23)
		)
		(stroke
			(width 0)
			(type default)
		)
	)
	(wire
		(pts
			(xy 278.13 135.89) (xy 306.07 135.89)
		)
		(stroke
			(width 0)
			(type default)
		)
	)
	(wire
		(pts
			(xy 170.18 176.53) (xy 179.07 176.53)
		)
		(stroke
			(width 0)
			(type default)
		)
	)
	(wire
		(pts
			(xy 105.41 208.28) (xy 105.41 209.55)
		)
		(stroke
			(width 0)
			(type default)
		)
	)
	(wire
		(pts
			(xy 170.18 204.47) (xy 179.07 204.47)
		)
		(stroke
			(width 0)
			(type default)
		)
	)
	(wire
		(pts
			(xy 72.39 102.87) (xy 72.39 104.14)
		)
		(stroke
			(width 0)
			(type default)
		)
	)
	(wire
		(pts
			(xy 110.49 176.53) (xy 125.73 176.53)
		)
		(stroke
			(width 0)
			(type default)
		)
	)
	(wire
		(pts
			(xy 180.34 55.88) (xy 180.34 66.04)
		)
		(stroke
			(width 0)
			(type default)
		)
	)
	(wire
		(pts
			(xy 110.49 194.31) (xy 125.73 194.31)
		)
		(stroke
			(width 0)
			(type default)
		)
	)
	(wire
		(pts
			(xy 247.65 153.67) (xy 306.07 153.67)
		)
		(stroke
			(width 0)
			(type default)
		)
	)
	(wire
		(pts
			(xy 177.8 91.44) (xy 187.96 91.44)
		)
		(stroke
			(width 0)
			(type default)
		)
	)
	(wire
		(pts
			(xy 198.12 91.44) (xy 198.12 110.49)
		)
		(stroke
			(width 0)
			(type default)
		)
	)
	(wire
		(pts
			(xy 288.29 125.73) (xy 302.26 125.73)
		)
		(stroke
			(width 0)
			(type default)
		)
	)
	(wire
		(pts
			(xy 90.17 173.99) (xy 90.17 175.26)
		)
		(stroke
			(width 0)
			(type default)
		)
	)
	(wire
		(pts
			(xy 245.11 151.13) (xy 245.11 172.72)
		)
		(stroke
			(width 0)
			(type default)
		)
	)
	(wire
		(pts
			(xy 228.6 166.37) (xy 228.6 172.72)
		)
		(stroke
			(width 0)
			(type default)
		)
	)
	(wire
		(pts
			(xy 190.5 209.55) (xy 190.5 210.82)
		)
		(stroke
			(width 0)
			(type default)
		)
	)
	(wire
		(pts
			(xy 175.26 91.44) (xy 177.8 91.44)
		)
		(stroke
			(width 0)
			(type default)
		)
	)
	(wire
		(pts
			(xy 116.84 228.6) (xy 116.84 229.87)
		)
		(stroke
			(width 0)
			(type default)
		)
	)
	(wire
		(pts
			(xy 226.06 168.91) (xy 226.06 172.72)
		)
		(stroke
			(width 0)
			(type default)
		)
	)
	(wire
		(pts
			(xy 233.68 110.49) (xy 306.07 110.49)
		)
		(stroke
			(width 0)
			(type default)
		)
	)
	(wire
		(pts
			(xy 172.72 199.39) (xy 179.07 199.39)
		)
		(stroke
			(width 0)
			(type default)
		)
	)
	(wire
		(pts
			(xy 90.17 180.34) (xy 90.17 182.88)
		)
		(stroke
			(width 0)
			(type default)
		)
	)
	(bus
		(pts
			(xy 109.22 175.26) (xy 109.22 177.8)
		)
		(stroke
			(width 0)
			(type default)
		)
	)
	(wire
		(pts
			(xy 226.06 68.58) (xy 223.52 68.58)
		)
		(stroke
			(width 0)
			(type default)
		)
	)
	(wire
		(pts
			(xy 88.9 209.55) (xy 91.44 209.55)
		)
		(stroke
			(width 0)
			(type default)
		)
	)
	(wire
		(pts
			(xy 285.75 123.19) (xy 304.8 123.19)
		)
		(stroke
			(width 0)
			(type default)
		)
	)
	(bus
		(pts
			(xy 267.97 121.92) (xy 266.7 120.65)
		)
		(stroke
			(width 0)
			(type default)
		)
	)
	(wire
		(pts
			(xy 101.6 151.13) (xy 125.73 151.13)
		)
		(stroke
			(width 0)
			(type default)
		)
	)
	(bus
		(pts
			(xy 71.12 148.59) (xy 73.66 148.59)
		)
		(stroke
			(width 0)
			(type default)
		)
	)
	(wire
		(pts
			(xy 96.52 209.55) (xy 97.79 209.55)
		)
		(stroke
			(width 0)
			(type default)
		)
	)
	(wire
		(pts
			(xy 302.26 125.73) (xy 306.07 125.73)
		)
		(stroke
			(width 0)
			(type default)
		)
	)
	(wire
		(pts
			(xy 151.13 186.69) (xy 172.72 186.69)
		)
		(stroke
			(width 0)
			(type default)
		)
	)
	(wire
		(pts
			(xy 294.64 176.53) (xy 306.07 176.53)
		)
		(stroke
			(width 0)
			(type default)
		)
	)
	(wire
		(pts
			(xy 110.49 186.69) (xy 125.73 186.69)
		)
		(stroke
			(width 0)
			(type default)
		)
	)
	(wire
		(pts
			(xy 280.67 97.79) (xy 280.67 115.57)
		)
		(stroke
			(width 0)
			(type default)
		)
	)
	(wire
		(pts
			(xy 173.99 189.23) (xy 173.99 186.69)
		)
		(stroke
			(width 0)
			(type default)
		)
	)
	(wire
		(pts
			(xy 90.17 161.29) (xy 92.71 158.75)
		)
		(stroke
			(width 0)
			(type default)
		)
	)
	(bus
		(pts
			(xy 109.22 165.1) (xy 107.95 163.83)
		)
		(stroke
			(width 0)
			(type default)
		)
	)
	(wire
		(pts
			(xy 92.71 161.29) (xy 99.06 161.29)
		)
		(stroke
			(width 0)
			(type default)
		)
	)
	(wire
		(pts
			(xy 180.34 66.04) (xy 208.28 66.04)
		)
		(stroke
			(width 0)
			(type default)
		)
	)
	(wire
		(pts
			(xy 289.56 176.53) (xy 289.56 175.26)
		)
		(stroke
			(width 0)
			(type default)
		)
	)
	(wire
		(pts
			(xy 151.13 168.91) (xy 226.06 168.91)
		)
		(stroke
			(width 0)
			(type default)
		)
	)
	(wire
		(pts
			(xy 72.39 101.6) (xy 72.39 102.87)
		)
		(stroke
			(width 0)
			(type default)
		)
	)
	(wire
		(pts
			(xy 151.13 184.15) (xy 170.18 184.15)
		)
		(stroke
			(width 0)
			(type default)
		)
	)
	(wire
		(pts
			(xy 304.8 123.19) (xy 304.8 128.27)
		)
		(stroke
			(width 0)
			(type default)
		)
	)
	(wire
		(pts
			(xy 177.8 91.44) (xy 177.8 95.25)
		)
		(stroke
			(width 0)
			(type default)
		)
	)
	(wire
		(pts
			(xy 184.15 176.53) (xy 193.04 176.53)
		)
		(stroke
			(width 0)
			(type default)
		)
	)
	(wire
		(pts
			(xy 189.23 68.58) (xy 177.8 68.58)
		)
		(stroke
			(width 0)
			(type default)
		)
	)
	(bus
		(pts
			(xy 267.97 121.92) (xy 267.97 124.46)
		)
		(stroke
			(width 0)
			(type default)
		)
	)
	(wire
		(pts
			(xy 151.13 161.29) (xy 176.53 161.29)
		)
		(stroke
			(width 0)
			(type default)
		)
	)
	(wire
		(pts
			(xy 189.23 49.53) (xy 189.23 50.8)
		)
		(stroke
			(width 0)
			(type default)
		)
	)
	(wire
		(pts
			(xy 242.57 171.45) (xy 242.57 172.72)
		)
		(stroke
			(width 0)
			(type default)
		)
	)
	(wire
		(pts
			(xy 110.49 201.93) (xy 125.73 201.93)
		)
		(stroke
			(width 0)
			(type default)
		)
	)
	(wire
		(pts
			(xy 189.23 55.88) (xy 189.23 68.58)
		)
		(stroke
			(width 0)
			(type default)
		)
	)
	(wire
		(pts
			(xy 137.16 237.49) (xy 135.89 237.49)
		)
		(stroke
			(width 0)
			(type default)
		)
	)
	(wire
		(pts
			(xy 105.41 102.87) (xy 105.41 104.14)
		)
		(stroke
			(width 0)
			(type default)
		)
	)
	(wire
		(pts
			(xy 193.04 196.85) (xy 193.04 201.93)
		)
		(stroke
			(width 0)
			(type default)
		)
	)
	(wire
		(pts
			(xy 193.04 181.61) (xy 193.04 186.69)
		)
		(stroke
			(width 0)
			(type default)
		)
	)
	(wire
		(pts
			(xy 180.34 228.6) (xy 165.1 228.6)
		)
		(stroke
			(width 0)
			(type default)
		)
	)
	(wire
		(pts
			(xy 273.05 143.51) (xy 306.07 143.51)
		)
		(stroke
			(width 0)
			(type default)
		)
	)
	(wire
		(pts
			(xy 273.05 143.51) (xy 273.05 172.72)
		)
		(stroke
			(width 0)
			(type default)
		)
	)
	(wire
		(pts
			(xy 250.19 158.75) (xy 250.19 172.72)
		)
		(stroke
			(width 0)
			(type default)
		)
	)
	(wire
		(pts
			(xy 261.62 71.12) (xy 261.62 69.85)
		)
		(stroke
			(width 0)
			(type default)
		)
	)
	(polyline
		(pts
			(xy 67.31 139.7) (xy 99.06 139.7)
		)
		(stroke
			(width 0)
			(type solid)
		)
	)
	(wire
		(pts
			(xy 151.13 166.37) (xy 228.6 166.37)
		)
		(stroke
			(width 0)
			(type default)
		)
	)
	(wire
		(pts
			(xy 187.96 120.65) (xy 187.96 121.92)
		)
		(stroke
			(width 0)
			(type default)
		)
	)
	(wire
		(pts
			(xy 193.04 201.93) (xy 193.04 207.01)
		)
		(stroke
			(width 0)
			(type default)
		)
	)
	(wire
		(pts
			(xy 76.2 151.13) (xy 96.52 151.13)
		)
		(stroke
			(width 0)
			(type default)
		)
	)
	(wire
		(pts
			(xy 297.18 76.2) (xy 297.18 77.47)
		)
		(stroke
			(width 0)
			(type default)
		)
	)
	(wire
		(pts
			(xy 97.79 209.55) (xy 97.79 210.82)
		)
		(stroke
			(width 0)
			(type default)
		)
	)
	(wire
		(pts
			(xy 151.13 151.13) (xy 245.11 151.13)
		)
		(stroke
			(width 0)
			(type default)
		)
	)
	(wire
		(pts
			(xy 287.02 63.5) (xy 287.02 64.77)
		)
		(stroke
			(width 0)
			(type default)
		)
	)
	(wire
		(pts
			(xy 236.22 171.45) (xy 242.57 171.45)
		)
		(stroke
			(width 0)
			(type default)
		)
	)
	(wire
		(pts
			(xy 269.24 123.19) (xy 285.75 123.19)
		)
		(stroke
			(width 0)
			(type default)
		)
	)
	(wire
		(pts
			(xy 181.61 161.29) (xy 252.73 161.29)
		)
		(stroke
			(width 0)
			(type default)
		)
	)
	(wire
		(pts
			(xy 184.15 201.93) (xy 193.04 201.93)
		)
		(stroke
			(width 0)
			(type default)
		)
	)
	(wire
		(pts
			(xy 283.21 118.11) (xy 306.07 118.11)
		)
		(stroke
			(width 0)
			(type default)
		)
	)
	(wire
		(pts
			(xy 173.99 194.31) (xy 173.99 191.77)
		)
		(stroke
			(width 0)
			(type default)
		)
	)
	(wire
		(pts
			(xy 184.15 184.15) (xy 190.5 184.15)
		)
		(stroke
			(width 0)
			(type default)
		)
	)
	(bus
		(pts
			(xy 74.93 149.86) (xy 74.93 152.4)
		)
		(stroke
			(width 0)
			(type default)
		)
	)
	(wire
		(pts
			(xy 232.41 73.66) (xy 226.06 73.66)
		)
		(stroke
			(width 0)
			(type default)
		)
	)
	(wire
		(pts
			(xy 93.98 102.87) (xy 93.98 104.14)
		)
		(stroke
			(width 0)
			(type default)
		)
	)
	(wire
		(pts
			(xy 180.34 48.26) (xy 180.34 50.8)
		)
		(stroke
			(width 0)
			(type default)
		)
	)
	(wire
		(pts
			(xy 184.15 199.39) (xy 190.5 199.39)
		)
		(stroke
			(width 0)
			(type default)
		)
	)
	(wire
		(pts
			(xy 151.13 146.05) (xy 176.53 146.05)
		)
		(stroke
			(width 0)
			(type default)
		)
	)
	(wire
		(pts
			(xy 245.11 151.13) (xy 306.07 151.13)
		)
		(stroke
			(width 0)
			(type default)
		)
	)
	(bus
		(pts
			(xy 109.22 198.12) (xy 109.22 200.66)
		)
		(stroke
			(width 0)
			(type default)
		)
	)
	(wire
		(pts
			(xy 152.4 209.55) (xy 152.4 210.82)
		)
		(stroke
			(width 0)
			(type default)
		)
	)
	(wire
		(pts
			(xy 193.04 176.53) (xy 193.04 181.61)
		)
		(stroke
			(width 0)
			(type default)
		)
	)
	(wire
		(pts
			(xy 289.56 168.91) (xy 289.56 170.18)
		)
		(stroke
			(width 0)
			(type default)
		)
	)
	(polyline
		(pts
			(xy 99.06 127) (xy 99.06 143.51)
		)
		(stroke
			(width 0)
			(type solid)
		)
	)
	(bus
		(pts
			(xy 88.9 163.83) (xy 107.95 163.83)
		)
		(stroke
			(width 0)
			(type default)
		)
	)
	(bus
		(pts
			(xy 63.5 116.84) (xy 66.04 116.84)
		)
		(stroke
			(width 0)
			(type default)
		)
	)
	(wire
		(pts
			(xy 184.15 191.77) (xy 193.04 191.77)
		)
		(stroke
			(width 0)
			(type default)
		)
	)
	(wire
		(pts
			(xy 116.84 240.03) (xy 116.84 241.3)
		)
		(stroke
			(width 0)
			(type default)
		)
	)
	(wire
		(pts
			(xy 297.18 63.5) (xy 297.18 64.77)
		)
		(stroke
			(width 0)
			(type default)
		)
	)
	(wire
		(pts
			(xy 288.29 176.53) (xy 288.29 177.8)
		)
		(stroke
			(width 0)
			(type default)
		)
	)
	(wire
		(pts
			(xy 261.62 171.45) (xy 267.97 171.45)
		)
		(stroke
			(width 0)
			(type default)
		)
	)
	(wire
		(pts
			(xy 83.82 102.87) (xy 93.98 102.87)
		)
		(stroke
			(width 0)
			(type default)
		)
	)
	(bus
		(pts
			(xy 74.93 152.4) (xy 74.93 157.48)
		)
		(stroke
			(width 0)
			(type default)
		)
	)
	(wire
		(pts
			(xy 115.57 102.87) (xy 115.57 104.14)
		)
		(stroke
			(width 0)
			(type default)
		)
	)
	(wire
		(pts
			(xy 110.49 166.37) (xy 125.73 166.37)
		)
		(stroke
			(width 0)
			(type default)
		)
	)
	(wire
		(pts
			(xy 110.49 199.39) (xy 125.73 199.39)
		)
		(stroke
			(width 0)
			(type default)
		)
	)
	(wire
		(pts
			(xy 306.07 123.19) (xy 304.8 123.19)
		)
		(stroke
			(width 0)
			(type default)
		)
	)
	(wire
		(pts
			(xy 151.13 194.31) (xy 172.72 194.31)
		)
		(stroke
			(width 0)
			(type default)
		)
	)
	(wire
		(pts
			(xy 143.51 228.6) (xy 160.02 228.6)
		)
		(stroke
			(width 0)
			(type default)
		)
	)
	(wire
		(pts
			(xy 172.72 196.85) (xy 172.72 199.39)
		)
		(stroke
			(width 0)
			(type default)
		)
	)
	(wire
		(pts
			(xy 226.06 168.91) (xy 289.56 168.91)
		)
		(stroke
			(width 0)
			(type default)
		)
	)
	(wire
		(pts
			(xy 76.2 161.29) (xy 90.17 161.29)
		)
		(stroke
			(width 0)
			(type default)
		)
	)
	(wire
		(pts
			(xy 212.09 173.99) (xy 212.09 171.45)
		)
		(stroke
			(width 0)
			(type default)
		)
	)
	(wire
		(pts
			(xy 170.18 179.07) (xy 179.07 179.07)
		)
		(stroke
			(width 0)
			(type default)
		)
	)
	(wire
		(pts
			(xy 287.02 166.37) (xy 287.02 170.18)
		)
		(stroke
			(width 0)
			(type default)
		)
	)
	(wire
		(pts
			(xy 76.2 185.42) (xy 90.17 185.42)
		)
		(stroke
			(width 0)
			(type default)
		)
	)
	(wire
		(pts
			(xy 226.06 73.66) (xy 226.06 68.58)
		)
		(stroke
			(width 0)
			(type default)
		)
	)
	(bus
		(pts
			(xy 74.93 149.86) (xy 73.66 148.59)
		)
		(stroke
			(width 0)
			(type default)
		)
	)
	(wire
		(pts
			(xy 143.51 240.03) (xy 143.51 241.3)
		)
		(stroke
			(width 0)
			(type default)
		)
	)
	(wire
		(pts
			(xy 204.47 68.58) (xy 204.47 69.85)
		)
		(stroke
			(width 0)
			(type default)
		)
	)
	(wire
		(pts
			(xy 232.41 72.39) (xy 232.41 73.66)
		)
		(stroke
			(width 0)
			(type default)
		)
	)
	(wire
		(pts
			(xy 151.13 199.39) (xy 168.91 199.39)
		)
		(stroke
			(width 0)
			(type default)
		)
	)
	(wire
		(pts
			(xy 116.84 220.98) (xy 116.84 222.25)
		)
		(stroke
			(width 0)
			(type default)
		)
	)
	(label "USBSS1_RX_C_N"
		(at 124.46 153.67 180)
		(effects
			(font
				(size 1.1 1.1)
			)
			(justify right bottom)
		)
	)
	(label "USBSS1_RX_C_P"
		(at 124.46 151.13 180)
		(effects
			(font
				(size 1.1 1.1)
			)
			(justify right bottom)
		)
	)
	(label "USBSS1.RX-"
		(at 77.47 153.67 0)
		(effects
			(font
				(size 1.27 1.27)
			)
			(justify left bottom)
		)
	)
	(label "USBSS1.TX-"
		(at 77.47 161.29 0)
		(effects
			(font
				(size 1.27 1.27)
			)
			(justify left bottom)
		)
	)
	(label "USBC1_TX1_P"
		(at 153.67 143.51 0)
		(effects
			(font
				(size 1.27 1.27)
			)
			(justify left bottom)
		)
	)
	(label "I2C_{SYS}.SDA"
		(at 69.85 121.92 0)
		(effects
			(font
				(size 1.27 1.27)
			)
			(justify left bottom)
		)
	)
	(label "USBC1_SBU_P"
		(at 153.67 168.91 0)
		(effects
			(font
				(size 1.27 1.27)
			)
			(justify left bottom)
		)
	)
	(label "USBC1_SSEQ0"
		(at 153.67 186.69 0)
		(effects
			(font
				(size 1.27 1.27)
			)
			(justify left bottom)
		)
	)
	(label "USBC1_CONN_TX2_N"
		(at 189.23 161.29 0)
		(effects
			(font
				(size 1.27 1.27)
			)
			(justify left bottom)
		)
	)
	(label "DP0.HPD"
		(at 179.07 228.6 180)
		(effects
			(font
				(size 1.27 1.27)
			)
			(justify right bottom)
		)
	)
	(label "USBC1_CC2"
		(at 237.49 118.11 0)
		(effects
			(font
				(size 1.27 1.27)
			)
			(justify left bottom)
		)
	)
	(label "USBC1_DPEQ1"
		(at 153.67 194.31 0)
		(effects
			(font
				(size 1.27 1.27)
			)
			(justify left bottom)
		)
	)
	(label "USBC1_CONN_TX2_P"
		(at 189.23 158.75 0)
		(effects
			(font
				(size 1.27 1.27)
			)
			(justify left bottom)
		)
	)
	(label "DP0.AUX+"
		(at 76.2 185.42 0)
		(effects
			(font
				(size 1.27 1.27)
			)
			(justify left bottom)
		)
	)
	(label "DP0.TX0+"
		(at 111.76 176.53 0)
		(effects
			(font
				(size 1.27 1.27)
			)
			(justify left bottom)
		)
	)
	(label "USBC1_RX1_N"
		(at 153.67 138.43 0)
		(effects
			(font
				(size 1.27 1.27)
			)
			(justify left bottom)
		)
	)
	(label "USBC1_VBUS"
		(at 237.49 110.49 0)
		(effects
			(font
				(size 1.27 1.27)
			)
			(justify left bottom)
		)
	)
	(label "DP0.TX3+"
		(at 111.76 199.39 0)
		(effects
			(font
				(size 1.27 1.27)
			)
			(justify left bottom)
		)
	)
	(label "DP0.AUX-"
		(at 111.76 168.91 0)
		(effects
			(font
				(size 1.27 1.27)
			)
			(justify left bottom)
		)
	)
	(label "HPDIN"
		(at 119.38 209.55 0)
		(effects
			(font
				(size 1.27 1.27)
			)
			(justify left bottom)
		)
	)
	(label "USBC1_CC1"
		(at 237.49 115.57 0)
		(effects
			(font
				(size 1.27 1.27)
			)
			(justify left bottom)
		)
	)
	(label "USBC1_RX1_P"
		(at 153.67 135.89 0)
		(effects
			(font
				(size 1.27 1.27)
			)
			(justify left bottom)
		)
	)
	(label "USBSS1.RX+"
		(at 77.47 151.13 0)
		(effects
			(font
				(size 1.27 1.27)
			)
			(justify left bottom)
		)
	)
	(label "USBSS1_TX_C_P"
		(at 124.46 158.75 180)
		(effects
			(font
				(size 1.1 1.1)
			)
			(justify right bottom)
		)
	)
	(label "USBSS1.TX+"
		(at 77.47 158.75 0)
		(effects
			(font
				(size 1.27 1.27)
			)
			(justify left bottom)
		)
	)
	(label "USB1.D+"
		(at 270.51 123.19 0)
		(effects
			(font
				(size 1.27 1.27)
			)
			(justify left bottom)
		)
	)
	(label "USBC1_CONN_TX1_P"
		(at 189.23 143.51 0)
		(effects
			(font
				(size 1.27 1.27)
			)
			(justify left bottom)
		)
	)
	(label "DP0.TX0-"
		(at 111.76 179.07 0)
		(effects
			(font
				(size 1.27 1.27)
			)
			(justify left bottom)
		)
	)
	(label "USBSS1_TX_C_N"
		(at 124.46 161.29 180)
		(effects
			(font
				(size 1.1 1.1)
			)
			(justify right bottom)
		)
	)
	(label "USBC1_RX2_N"
		(at 153.67 153.67 0)
		(effects
			(font
				(size 1.27 1.27)
			)
			(justify left bottom)
		)
	)
	(label "USBC1_RX2_P"
		(at 153.67 151.13 0)
		(effects
			(font
				(size 1.27 1.27)
			)
			(justify left bottom)
		)
	)
	(label "USBC1_CONN_TX1_N"
		(at 189.23 146.05 0)
		(effects
			(font
				(size 1.27 1.27)
			)
			(justify left bottom)
		)
	)
	(label "USBC1_DPEQ0"
		(at 153.67 191.77 0)
		(effects
			(font
				(size 1.27 1.27)
			)
			(justify left bottom)
		)
	)
	(label "USBC1_SSEQ1"
		(at 153.67 189.23 0)
		(effects
			(font
				(size 1.27 1.27)
			)
			(justify left bottom)
		)
	)
	(label "USBC1_SBU_N"
		(at 153.67 166.37 0)
		(effects
			(font
				(size 1.27 1.27)
			)
			(justify left bottom)
		)
	)
	(label "USBC1_EQ1"
		(at 153.67 199.39 0)
		(effects
			(font
				(size 1.27 1.27)
			)
			(justify left bottom)
		)
	)
	(label "DP0.AUX-"
		(at 76.2 182.88 0)
		(effects
			(font
				(size 1.27 1.27)
			)
			(justify left bottom)
		)
	)
	(label "I2C_{SYS}.SCL"
		(at 69.85 119.38 0)
		(effects
			(font
				(size 1.27 1.27)
			)
			(justify left bottom)
		)
	)
	(label "USBC1_TX1_N"
		(at 153.67 146.05 0)
		(effects
			(font
				(size 1.27 1.27)
			)
			(justify left bottom)
		)
	)
	(label "DP0.TX1-"
		(at 111.76 186.69 0)
		(effects
			(font
				(size 1.27 1.27)
			)
			(justify left bottom)
		)
	)
	(label "USBC1_TX2_N"
		(at 153.67 161.29 0)
		(effects
			(font
				(size 1.27 1.27)
			)
			(justify left bottom)
		)
	)
	(label "DP0.TX1+"
		(at 111.76 184.15 0)
		(effects
			(font
				(size 1.27 1.27)
			)
			(justify left bottom)
		)
	)
	(label "USBC1_EQ0"
		(at 153.67 196.85 0)
		(effects
			(font
				(size 1.27 1.27)
			)
			(justify left bottom)
		)
	)
	(label "DP0.TX3-"
		(at 111.76 201.93 0)
		(effects
			(font
				(size 1.27 1.27)
			)
			(justify left bottom)
		)
	)
	(label "USBC1_I2C_EN"
		(at 153.67 184.15 0)
		(effects
			(font
				(size 1.27 1.27)
			)
			(justify left bottom)
		)
	)
	(label "DP0.TX2+"
		(at 111.76 191.77 0)
		(effects
			(font
				(size 1.27 1.27)
			)
			(justify left bottom)
		)
	)
	(label "DP0.AUX+"
		(at 111.76 166.37 0)
		(effects
			(font
				(size 1.27 1.27)
			)
			(justify left bottom)
		)
	)
	(label "USB1.D-"
		(at 270.51 125.73 0)
		(effects
			(font
				(size 1.27 1.27)
			)
			(justify left bottom)
		)
	)
	(label "USBC1_TX2_P"
		(at 153.67 158.75 0)
		(effects
			(font
				(size 1.27 1.27)
			)
			(justify left bottom)
		)
	)
	(label "DP0.TX2-"
		(at 111.76 194.31 0)
		(effects
			(font
				(size 1.27 1.27)
			)
			(justify left bottom)
		)
	)
	(hierarchical_label "USB1{USB}"
		(shape input)
		(at 264.16 120.65 180)
		(effects
			(font
				(size 1.27 1.27)
			)
			(justify right)
		)
	)
	(hierarchical_label "USBPD1_HV"
		(shape bidirectional)
		(at 175.26 91.44 180)
		(effects
			(font
				(size 1.27 1.27)
			)
			(justify right)
		)
	)
	(hierarchical_label "DP0{DP}"
		(shape input)
		(at 185.42 226.06 0)
		(effects
			(font
				(size 1.27 1.27)
			)
			(justify left)
		)
	)
	(hierarchical_label "I2C_{SYS}{I2C}"
		(shape bidirectional)
		(at 63.5 116.84 180)
		(effects
			(font
				(size 1.27 1.27)
			)
			(justify right)
		)
	)
	(hierarchical_label "USBC1_FLIP"
		(shape input)
		(at 114.3 138.43 180)
		(effects
			(font
				(size 1.27 1.27)
			)
			(justify right)
		)
	)
	(hierarchical_label "USBC1_CTL1"
		(shape input)
		(at 114.3 143.51 180)
		(effects
			(font
				(size 1.27 1.27)
			)
			(justify right)
		)
	)
	(hierarchical_label "DP0{DP}"
		(shape input)
		(at 88.9 163.83 180)
		(effects
			(font
				(size 1.27 1.27)
			)
			(justify right)
		)
	)
	(hierarchical_label "USBSS1{USBSS}"
		(shape bidirectional)
		(at 71.12 148.59 180)
		(effects
			(font
				(size 1.27 1.27)
			)
			(justify right)
		)
	)
	(hierarchical_label "USBC1_FLG"
		(shape output)
		(at 177.8 66.04 180)
		(effects
			(font
				(size 1.27 1.27)
			)
			(justify right)
		)
	)
	(hierarchical_label "USBC1_5V_PEN"
		(shape input)
		(at 177.8 68.58 180)
		(effects
			(font
				(size 1.27 1.27)
			)
			(justify right)
		)
	)
	(hierarchical_label "USBC1_CTL0"
		(shape input)
		(at 114.3 140.97 180)
		(effects
			(font
				(size 1.27 1.27)
			)
			(justify right)
		)
	)
	(hierarchical_label "USBC_HPD"
		(shape input)
		(at 88.9 209.55 180)
		(effects
			(font
				(size 1.27 1.27)
			)
			(justify right)
		)
	)
	(rule_area
		(polyline
			(pts
				(xy 209.3912 170.18) (xy 152.5587 170.18) (xy 152.4 133.35) (xy 209.2325 133.35)
			)
			(stroke
				(width 0)
				(type dash)
			)
			(fill
				(type none)
			)
		)
	)
	(rule_area
		(polyline
			(pts
				(xy 124.46 202.5649) (xy 110.49 202.565) (xy 110.49 163.83) (xy 124.46 163.8299)
			)
			(stroke
				(width 0)
				(type dash)
			)
			(fill
				(type none)
			)
		)
	)
	(rule_area
		(polyline
			(pts
				(xy 124.46 162.56) (xy 76.2 162.56) (xy 76.2 148.59) (xy 124.46 148.59)
			)
			(stroke
				(width 0)
				(type dash)
			)
			(fill
				(type none)
			)
		)
	)
	(rule_area
		(polyline
			(pts
				(xy 281.305 127) (xy 269.24 127) (xy 269.24 120.65) (xy 281.305 120.65)
			)
			(stroke
				(width 0)
				(type dash)
			)
			(fill
				(type none)
			)
		)
	)
	(netclass_flag ""
		(length 2.54)
		(shape round)
		(at 152.4 133.35 0)
		(effects
			(font
				(size 1.27 1.27)
			)
			(justify left bottom)
		)
		(property "Netclass" "85Ohm-diff_USB_SS"
			(at 153.416 130.81 0)
			(effects
				(font
					(size 1.27 1.27)
				)
				(justify left)
			)
		)
		(property "Component Class" ""
			(at -10.16 91.44 0)
			(effects
				(font
					(size 1.27 1.27)
					(italic yes)
				)
				(justify right)
			)
		)
	)
	(netclass_flag ""
		(length 2.54)
		(shape round)
		(at 110.49 170.18 90)
		(effects
			(font
				(size 1.27 1.27)
			)
			(justify left bottom)
		)
		(property "Netclass" "85Ohm-diff_DP"
			(at 92.456 168.148 0)
			(effects
				(font
					(size 1.27 1.27)
				)
				(justify left)
			)
		)
		(property "Component Class" ""
			(at 68.58 332.74 90)
			(effects
				(font
					(size 1.27 1.27)
					(italic yes)
				)
				(justify right)
			)
		)
	)
	(netclass_flag ""
		(length 2.54)
		(shape round)
		(at 76.2 148.59 0)
		(effects
			(font
				(size 1.27 1.27)
			)
			(justify left bottom)
		)
		(property "Netclass" "85Ohm-diff_USB_SS"
			(at 77.216 146.05 0)
			(effects
				(font
					(size 1.27 1.27)
				)
				(justify left)
			)
		)
		(property "Component Class" ""
			(at -86.36 106.68 0)
			(effects
				(font
					(size 1.27 1.27)
					(italic yes)
				)
				(justify right)
			)
		)
	)
	(netclass_flag ""
		(length 2.54)
		(shape round)
		(at 269.24 127 90)
		(effects
			(font
				(size 1.27 1.27)
			)
			(justify left bottom)
		)
		(property "Netclass" "90Ohm-diff_USB_2.0"
			(at 265.176 127 0)
			(effects
				(font
					(size 1.27 1.27)
				)
				(justify right)
			)
		)
		(property "Component Class" ""
			(at 227.33 289.56 90)
			(effects
				(font
					(size 1.27 1.27)
					(italic yes)
				)
				(justify right)
			)
		)
	)
	(symbol
		(lib_id "antmicropower:GND")
		(at 143.51 241.3 0)
		(mirror y)
		(unit 1)
		(exclude_from_sim no)
		(in_bom yes)
		(on_board yes)
		(dnp no)
		(property "Reference" "#PWR0641"
			(at 143.51 247.65 0)
			(effects
				(font
					(size 1.27 1.27)
				)
				(justify left bottom)
				(hide yes)
			)
		)
		(property "Value" "GND"
			(at 143.51 245.11 0)
			(effects
				(font
					(size 1.27 1.27)
					(thickness 0.15)
				)
			)
		)
		(property "Footprint" ""
			(at 134.62 248.92 0)
			(effects
				(font
					(size 1.27 1.27)
					(thickness 0.15)
				)
				(justify left bottom)
				(hide yes)
			)
		)
		(property "Datasheet" ""
			(at 134.62 254 0)
			(effects
				(font
					(size 1.27 1.27)
					(thickness 0.15)
				)
				(justify left bottom)
				(hide yes)
			)
		)
		(property "Description" ""
			(at 143.51 241.3 0)
			(effects
				(font
					(size 1.27 1.27)
				)
				(hide yes)
			)
		)
		(property "Author" "Antmicro"
			(at 134.62 248.92 0)
			(effects
				(font
					(size 1.27 1.27)
					(thickness 0.15)
				)
				(justify left bottom)
				(hide yes)
			)
		)
		(property "License" "Apache-2.0"
			(at 134.62 251.46 0)
			(effects
				(font
					(size 1.27 1.27)
					(thickness 0.15)
				)
				(justify left bottom)
				(hide yes)
			)
		)
		(pin "1"
		)
		(instances
			(project "jetson-agx-thor-baseboard"
				(path ""
					(reference "#PWR0641")
					(unit 1)
				)
			)
		)
	)
	(symbol
		(lib_id "antmicroResistors0402:R_0R_0402")
		(at 119.38 132.08 90)
		(unit 1)
		(exclude_from_sim no)
		(in_bom no)
		(on_board yes)
		(dnp yes)
		(property "Reference" "R122"
			(at 121.285 128.27 90)
			(effects
				(font
					(size 1.27 1.27)
				)
				(justify right)
			)
		)
		(property "Value" "R_0R_0402"
			(at 132.08 111.76 0)
			(effects
				(font
					(size 1.27 1.27)
					(thickness 0.15)
				)
				(justify left bottom)
				(hide yes)
			)
		)
		(property "Footprint" "antmicro-footprints:R_0402_1005Metric"
			(at 134.62 111.76 0)
			(effects
				(font
					(size 1.27 1.27)
					(thickness 0.15)
				)
				(justify left bottom)
				(hide yes)
			)
		)
		(property "Datasheet" "https://industrial.panasonic.com/cdbs/www-data/pdf/RDA0000/AOA0000C301.pdf"
			(at 137.16 111.76 0)
			(effects
				(font
					(size 1.27 1.27)
					(thickness 0.15)
				)
				(justify left bottom)
				(hide yes)
			)
		)
		(property "Description" "SMD Chip Resistor, Jumper, 0 ohm, 100 mW, 0402 [1005 Metric], Thick Film, General Purpose"
			(at 119.38 132.08 0)
			(effects
				(font
					(size 1.27 1.27)
				)
				(hide yes)
			)
		)
		(property "Manufacturer" "Panasonic"
			(at 142.24 111.76 0)
			(effects
				(font
					(size 1.27 1.27)
					(thickness 0.15)
				)
				(justify left bottom)
				(hide yes)
			)
		)
		(property "MPN" "ERJ2GE0R00X"
			(at 139.7 111.76 0)
			(effects
				(font
					(size 1.27 1.27)
					(thickness 0.15)
				)
				(justify left bottom)
				(hide yes)
			)
		)
		(property "Val" "0R"
			(at 121.285 130.81 90)
			(effects
				(font
					(size 1.27 1.27)
					(thickness 0.15)
				)
				(justify right)
			)
		)
		(property "License" "Apache-2.0"
			(at 144.78 111.76 0)
			(effects
				(font
					(size 1.27 1.27)
					(thickness 0.15)
				)
				(justify left bottom)
				(hide yes)
			)
		)
		(property "Author" "Antmicro"
			(at 147.32 111.76 0)
			(effects
				(font
					(size 1.27 1.27)
					(thickness 0.15)
				)
				(justify left bottom)
				(hide yes)
			)
		)
		(property "Tolerance" "~"
			(at 129.54 111.76 0)
			(effects
				(font
					(size 1.27 1.27)
				)
				(justify left bottom)
				(hide yes)
			)
		)
		(property "Current" "1A"
			(at 149.86 111.76 0)
			(effects
				(font
					(size 1.27 1.27)
					(thickness 0.15)
				)
				(justify left bottom)
				(hide yes)
			)
		)
		(pin "1"
		)
		(pin "2"
		)
		(instances
			(project "jetson-agx-thor-baseboard"
				(path ""
					(reference "R122")
					(unit 1)
				)
			)
		)
	)
	(symbol
		(lib_id "antmicroResistors0402:R_1k_0402")
		(at 179.07 194.31 0)
		(unit 1)
		(exclude_from_sim no)
		(in_bom no)
		(on_board yes)
		(dnp yes)
		(property "Reference" "R135"
			(at 184.785 193.675 0)
			(effects
				(font
					(size 1.27 1.27)
				)
				(justify left bottom)
			)
		)
		(property "Value" "R_1k_0402"
			(at 199.39 207.01 0)
			(effects
				(font
					(size 1.27 1.27)
					(thickness 0.15)
				)
				(justify left bottom)
				(hide yes)
			)
		)
		(property "Footprint" "antmicro-footprints:R_0402_1005Metric"
			(at 199.39 209.55 0)
			(effects
				(font
					(size 1.27 1.27)
					(thickness 0.15)
				)
				(justify left bottom)
				(hide yes)
			)
		)
		(property "Datasheet" "https://www.bourns.com/docs/product-datasheets/cr.pdf"
			(at 199.39 212.09 0)
			(effects
				(font
					(size 1.27 1.27)
					(thickness 0.15)
				)
				(justify left bottom)
				(hide yes)
			)
		)
		(property "Description" "SMD Chip Resistor, 1 kohm, ± 1%, 63 mW, 0402 [1005 Metric], Thick Film, General Purpose"
			(at 179.07 194.31 0)
			(effects
				(font
					(size 1.27 1.27)
				)
				(hide yes)
			)
		)
		(property "Manufacturer" "Bourns"
			(at 199.39 217.17 0)
			(effects
				(font
					(size 1.27 1.27)
					(thickness 0.15)
				)
				(justify left bottom)
				(hide yes)
			)
		)
		(property "MPN" "CR0402-FX-1001GLF"
			(at 199.39 214.63 0)
			(effects
				(font
					(size 1.27 1.27)
					(thickness 0.15)
				)
				(justify left bottom)
				(hide yes)
			)
		)
		(property "Val" "1k"
			(at 176.53 193.675 0)
			(effects
				(font
					(size 1.27 1.27)
					(thickness 0.15)
				)
				(justify left bottom)
			)
		)
		(property "License" "Apache-2.0"
			(at 199.39 219.71 0)
			(effects
				(font
					(size 1.27 1.27)
					(thickness 0.15)
				)
				(justify left bottom)
				(hide yes)
			)
		)
		(property "Author" "Antmicro"
			(at 199.39 222.25 0)
			(effects
				(font
					(size 1.27 1.27)
					(thickness 0.15)
				)
				(justify left bottom)
				(hide yes)
			)
		)
		(property "Tolerance" "1%"
			(at 199.39 204.47 0)
			(effects
				(font
					(size 1.27 1.27)
				)
				(justify left bottom)
				(hide yes)
			)
		)
		(pin "1"
		)
		(pin "2"
		)
		(instances
			(project "jetson-agx-thor-baseboard"
				(path ""
					(reference "R135")
					(unit 1)
				)
			)
		)
	)
	(symbol
		(lib_id "antmicroCapacitors0402:C_100n_0402")
		(at 172.72 158.75 0)
		(mirror x)
		(unit 1)
		(exclude_from_sim no)
		(in_bom yes)
		(on_board yes)
		(dnp no)
		(property "Reference" "C142"
			(at 181.61 157.48 0)
			(effects
				(font
					(size 1.27 1.27)
				)
				(justify right)
			)
		)
		(property "Value" "C_100n_0402"
			(at 193.04 148.59 0)
			(effects
				(font
					(size 1.27 1.27)
					(thickness 0.15)
				)
				(justify left bottom)
				(hide yes)
			)
		)
		(property "Footprint" "antmicro-footprints:C_0402_1005Metric"
			(at 193.04 146.05 0)
			(effects
				(font
					(size 1.27 1.27)
					(thickness 0.15)
				)
				(justify left bottom)
				(hide yes)
			)
		)
		(property "Datasheet" "https://www.murata.com/products/productdetail?partno=GRM155R61H104KE14%23"
			(at 193.04 143.51 0)
			(effects
				(font
					(size 1.27 1.27)
					(thickness 0.15)
				)
				(justify left bottom)
				(hide yes)
			)
		)
		(property "Description" "SMD Multilayer Ceramic Capacitor, 0.1 µF, 50 V, 0402 [1005 Metric], ± 10%, X5R, GRM Series"
			(at 172.72 158.75 0)
			(effects
				(font
					(size 1.27 1.27)
				)
				(hide yes)
			)
		)
		(property "Manufacturer" "Murata"
			(at 193.04 138.43 0)
			(effects
				(font
					(size 1.27 1.27)
					(thickness 0.15)
				)
				(justify left bottom)
				(hide yes)
			)
		)
		(property "MPN" "GRM155R61H104KE14D"
			(at 193.04 140.97 0)
			(effects
				(font
					(size 1.27 1.27)
					(thickness 0.15)
				)
				(justify left bottom)
				(hide yes)
			)
		)
		(property "Val" "100n"
			(at 174.498 160.02 0)
			(effects
				(font
					(size 1.27 1.27)
					(thickness 0.15)
				)
				(justify right)
			)
		)
		(property "License" "Apache-2.0"
			(at 193.04 135.89 0)
			(effects
				(font
					(size 1.27 1.27)
					(thickness 0.15)
				)
				(justify left bottom)
				(hide yes)
			)
		)
		(property "Author" "Antmicro"
			(at 193.04 133.35 0)
			(effects
				(font
					(size 1.27 1.27)
					(thickness 0.15)
				)
				(justify left bottom)
				(hide yes)
			)
		)
		(property "Voltage" "50V"
			(at 193.04 130.81 0)
			(effects
				(font
					(size 1.27 1.27)
				)
				(justify left bottom)
				(hide yes)
			)
		)
		(property "Dielectric" "X5R"
			(at 193.04 128.27 0)
			(effects
				(font
					(size 1.27 1.27)
				)
				(justify left bottom)
				(hide yes)
			)
		)
		(pin "1"
		)
		(pin "2"
		)
		(instances
			(project "jetson-agx-thor-baseboard"
				(path ""
					(reference "C142")
					(unit 1)
				)
			)
		)
	)
	(symbol
		(lib_id "antmicroCapacitors0402:C_100n_0402")
		(at 176.53 146.05 0)
		(mirror x)
		(unit 1)
		(exclude_from_sim no)
		(in_bom yes)
		(on_board yes)
		(dnp no)
		(property "Reference" "C144"
			(at 185.166 144.78 0)
			(effects
				(font
					(size 1.27 1.27)
				)
				(justify right)
			)
		)
		(property "Value" "C_100n_0402"
			(at 196.85 135.89 0)
			(effects
				(font
					(size 1.27 1.27)
					(thickness 0.15)
				)
				(justify left bottom)
				(hide yes)
			)
		)
		(property "Footprint" "antmicro-footprints:C_0402_1005Metric"
			(at 196.85 133.35 0)
			(effects
				(font
					(size 1.27 1.27)
					(thickness 0.15)
				)
				(justify left bottom)
				(hide yes)
			)
		)
		(property "Datasheet" "https://www.murata.com/products/productdetail?partno=GRM155R61H104KE14%23"
			(at 196.85 130.81 0)
			(effects
				(font
					(size 1.27 1.27)
					(thickness 0.15)
				)
				(justify left bottom)
				(hide yes)
			)
		)
		(property "Description" "SMD Multilayer Ceramic Capacitor, 0.1 µF, 50 V, 0402 [1005 Metric], ± 10%, X5R, GRM Series"
			(at 176.53 146.05 0)
			(effects
				(font
					(size 1.27 1.27)
				)
				(hide yes)
			)
		)
		(property "Manufacturer" "Murata"
			(at 196.85 125.73 0)
			(effects
				(font
					(size 1.27 1.27)
					(thickness 0.15)
				)
				(justify left bottom)
				(hide yes)
			)
		)
		(property "MPN" "GRM155R61H104KE14D"
			(at 196.85 128.27 0)
			(effects
				(font
					(size 1.27 1.27)
					(thickness 0.15)
				)
				(justify left bottom)
				(hide yes)
			)
		)
		(property "Val" "100n"
			(at 178.054 147.32 0)
			(effects
				(font
					(size 1.27 1.27)
					(thickness 0.15)
				)
				(justify right)
			)
		)
		(property "License" "Apache-2.0"
			(at 196.85 123.19 0)
			(effects
				(font
					(size 1.27 1.27)
					(thickness 0.15)
				)
				(justify left bottom)
				(hide yes)
			)
		)
		(property "Author" "Antmicro"
			(at 196.85 120.65 0)
			(effects
				(font
					(size 1.27 1.27)
					(thickness 0.15)
				)
				(justify left bottom)
				(hide yes)
			)
		)
		(property "Voltage" "50V"
			(at 196.85 118.11 0)
			(effects
				(font
					(size 1.27 1.27)
				)
				(justify left bottom)
				(hide yes)
			)
		)
		(property "Dielectric" "X5R"
			(at 196.85 115.57 0)
			(effects
				(font
					(size 1.27 1.27)
				)
				(justify left bottom)
				(hide yes)
			)
		)
		(pin "1"
		)
		(pin "2"
		)
		(instances
			(project "jetson-agx-thor-baseboard"
				(path ""
					(reference "C144")
					(unit 1)
				)
			)
		)
	)
	(symbol
		(lib_id "antmicroResistors0402:R_1k_0402")
		(at 179.07 199.39 0)
		(unit 1)
		(exclude_from_sim no)
		(in_bom yes)
		(on_board yes)
		(dnp no)
		(property "Reference" "R137"
			(at 184.785 198.755 0)
			(effects
				(font
					(size 1.27 1.27)
				)
				(justify left bottom)
			)
		)
		(property "Value" "R_1k_0402"
			(at 199.39 212.09 0)
			(effects
				(font
					(size 1.27 1.27)
					(thickness 0.15)
				)
				(justify left bottom)
				(hide yes)
			)
		)
		(property "Footprint" "antmicro-footprints:R_0402_1005Metric"
			(at 199.39 214.63 0)
			(effects
				(font
					(size 1.27 1.27)
					(thickness 0.15)
				)
				(justify left bottom)
				(hide yes)
			)
		)
		(property "Datasheet" "https://www.bourns.com/docs/product-datasheets/cr.pdf"
			(at 199.39 217.17 0)
			(effects
				(font
					(size 1.27 1.27)
					(thickness 0.15)
				)
				(justify left bottom)
				(hide yes)
			)
		)
		(property "Description" "SMD Chip Resistor, 1 kohm, ± 1%, 63 mW, 0402 [1005 Metric], Thick Film, General Purpose"
			(at 179.07 199.39 0)
			(effects
				(font
					(size 1.27 1.27)
				)
				(hide yes)
			)
		)
		(property "Manufacturer" "Bourns"
			(at 199.39 222.25 0)
			(effects
				(font
					(size 1.27 1.27)
					(thickness 0.15)
				)
				(justify left bottom)
				(hide yes)
			)
		)
		(property "MPN" "CR0402-FX-1001GLF"
			(at 199.39 219.71 0)
			(effects
				(font
					(size 1.27 1.27)
					(thickness 0.15)
				)
				(justify left bottom)
				(hide yes)
			)
		)
		(property "Val" "1k"
			(at 176.53 198.755 0)
			(effects
				(font
					(size 1.27 1.27)
					(thickness 0.15)
				)
				(justify left bottom)
			)
		)
		(property "License" "Apache-2.0"
			(at 199.39 224.79 0)
			(effects
				(font
					(size 1.27 1.27)
					(thickness 0.15)
				)
				(justify left bottom)
				(hide yes)
			)
		)
		(property "Author" "Antmicro"
			(at 199.39 227.33 0)
			(effects
				(font
					(size 1.27 1.27)
					(thickness 0.15)
				)
				(justify left bottom)
				(hide yes)
			)
		)
		(property "Tolerance" "1%"
			(at 199.39 209.55 0)
			(effects
				(font
					(size 1.27 1.27)
				)
				(justify left bottom)
				(hide yes)
			)
		)
		(pin "1"
		)
		(pin "2"
		)
		(instances
			(project "jetson-agx-thor-baseboard"
				(path ""
					(reference "R137")
					(unit 1)
				)
			)
		)
	)
	(symbol
		(lib_id "antmicropower:+1V8")
		(at 143.51 220.98 0)
		(unit 1)
		(exclude_from_sim no)
		(in_bom yes)
		(on_board yes)
		(dnp no)
		(property "Reference" "#PWR0640"
			(at 143.51 224.79 0)
			(effects
				(font
					(size 1.27 1.27)
				)
				(justify left bottom)
				(hide yes)
			)
		)
		(property "Value" "+1V8"
			(at 140.335 217.17 0)
			(effects
				(font
					(size 1.27 1.27)
					(thickness 0.15)
				)
				(justify left)
			)
		)
		(property "Footprint" ""
			(at 158.75 228.6 0)
			(effects
				(font
					(size 1.27 1.27)
					(thickness 0.15)
				)
				(justify left bottom)
				(hide yes)
			)
		)
		(property "Datasheet" ""
			(at 158.75 231.14 0)
			(effects
				(font
					(size 1.27 1.27)
					(thickness 0.15)
				)
				(justify left bottom)
				(hide yes)
			)
		)
		(property "Description" ""
			(at 143.51 220.98 0)
			(effects
				(font
					(size 1.27 1.27)
				)
				(hide yes)
			)
		)
		(property "Author" "Antmicro"
			(at 158.75 226.06 0)
			(effects
				(font
					(size 1.27 1.27)
					(thickness 0.15)
				)
				(justify left bottom)
				(hide yes)
			)
		)
		(property "License" "Apache-2.0"
			(at 158.75 228.6 0)
			(effects
				(font
					(size 1.27 1.27)
					(thickness 0.15)
				)
				(justify left bottom)
				(hide yes)
			)
		)
		(pin "1"
		)
		(instances
			(project "jetson-agx-thor-baseboard"
				(path ""
					(reference "#PWR0640")
					(unit 1)
				)
			)
		)
	)
	(symbol
		(lib_id "antmicroResistors0402:R_1k_0402")
		(at 179.07 176.53 0)
		(unit 1)
		(exclude_from_sim no)
		(in_bom no)
		(on_board yes)
		(dnp yes)
		(property "Reference" "R128"
			(at 184.785 175.895 0)
			(effects
				(font
					(size 1.27 1.27)
				)
				(justify left bottom)
			)
		)
		(property "Value" "R_1k_0402"
			(at 199.39 189.23 0)
			(effects
				(font
					(size 1.27 1.27)
					(thickness 0.15)
				)
				(justify left bottom)
				(hide yes)
			)
		)
		(property "Footprint" "antmicro-footprints:R_0402_1005Metric"
			(at 199.39 191.77 0)
			(effects
				(font
					(size 1.27 1.27)
					(thickness 0.15)
				)
				(justify left bottom)
				(hide yes)
			)
		)
		(property "Datasheet" "https://www.bourns.com/docs/product-datasheets/cr.pdf"
			(at 199.39 194.31 0)
			(effects
				(font
					(size 1.27 1.27)
					(thickness 0.15)
				)
				(justify left bottom)
				(hide yes)
			)
		)
		(property "Description" "SMD Chip Resistor, 1 kohm, ± 1%, 63 mW, 0402 [1005 Metric], Thick Film, General Purpose"
			(at 179.07 176.53 0)
			(effects
				(font
					(size 1.27 1.27)
				)
				(hide yes)
			)
		)
		(property "Manufacturer" "Bourns"
			(at 199.39 199.39 0)
			(effects
				(font
					(size 1.27 1.27)
					(thickness 0.15)
				)
				(justify left bottom)
				(hide yes)
			)
		)
		(property "MPN" "CR0402-FX-1001GLF"
			(at 199.39 196.85 0)
			(effects
				(font
					(size 1.27 1.27)
					(thickness 0.15)
				)
				(justify left bottom)
				(hide yes)
			)
		)
		(property "Val" "1k"
			(at 176.53 175.895 0)
			(effects
				(font
					(size 1.27 1.27)
					(thickness 0.15)
				)
				(justify left bottom)
			)
		)
		(property "License" "Apache-2.0"
			(at 199.39 201.93 0)
			(effects
				(font
					(size 1.27 1.27)
					(thickness 0.15)
				)
				(justify left bottom)
				(hide yes)
			)
		)
		(property "Author" "Antmicro"
			(at 199.39 204.47 0)
			(effects
				(font
					(size 1.27 1.27)
					(thickness 0.15)
				)
				(justify left bottom)
				(hide yes)
			)
		)
		(property "Tolerance" "1%"
			(at 199.39 186.69 0)
			(effects
				(font
					(size 1.27 1.27)
				)
				(justify left bottom)
				(hide yes)
			)
		)
		(pin "1"
		)
		(pin "2"
		)
		(instances
			(project "jetson-agx-thor-baseboard"
				(path ""
					(reference "R128")
					(unit 1)
				)
			)
		)
	)
	(symbol
		(lib_id "antmicroTVSDiodes:ESDA25P35-1U1M")
		(at 261.62 64.77 270)
		(unit 1)
		(exclude_from_sim no)
		(in_bom yes)
		(on_board yes)
		(dnp no)
		(property "Reference" "D22"
			(at 263.525 66.04 90)
			(effects
				(font
					(size 1.27 1.27)
				)
				(justify left)
			)
		)
		(property "Value" "ESDA25P35-1U1M"
			(at 246.38 86.36 0)
			(effects
				(font
					(size 1.27 1.27)
					(thickness 0.15)
				)
				(justify left bottom)
				(hide yes)
			)
		)
		(property "Footprint" "antmicro-footprints:QFN-2L_1.6x1x0.55mm"
			(at 251.46 88.9 0)
			(effects
				(font
					(size 1.27 1.27)
					(thickness 0.15)
				)
				(justify left bottom)
				(hide yes)
			)
		)
		(property "Datasheet" "https://www.st.com/resource/en/datasheet/esda25p35-1u1m.pdf"
			(at 248.92 88.9 0)
			(effects
				(font
					(size 1.27 1.27)
					(thickness 0.15)
				)
				(justify left bottom)
				(hide yes)
			)
		)
		(property "Description" "Unidirectional TVS, 30 kV, QFN-2L, 22 V, 195 pF"
			(at 236.22 88.9 0)
			(effects
				(font
					(size 1.27 1.27)
				)
				(justify left bottom)
				(hide yes)
			)
		)
		(property "Manufacturer" "STMicroelectronics"
			(at 243.84 88.9 0)
			(effects
				(font
					(size 1.27 1.27)
					(thickness 0.15)
				)
				(justify left bottom)
				(hide yes)
			)
		)
		(property "MPN" "ESDA25P35-1U1M"
			(at 257.81 66.04 0)
			(effects
				(font
					(size 1.27 1.27)
					(thickness 0.15)
				)
				(justify left bottom)
			)
		)
		(property "Author" "Antmicro"
			(at 241.3 88.9 0)
			(effects
				(font
					(size 1.27 1.27)
					(thickness 0.15)
				)
				(justify left bottom)
				(hide yes)
			)
		)
		(property "License" "Apache-2.0"
			(at 238.76 88.9 0)
			(effects
				(font
					(size 1.27 1.27)
					(thickness 0.15)
				)
				(justify left bottom)
				(hide yes)
			)
		)
		(pin "1"
		)
		(pin "2"
		)
		(instances
			(project "jetson-agx-thor-baseboard"
				(path ""
					(reference "D22")
					(unit 1)
				)
			)
		)
	)
	(symbol
		(lib_id "antmicroTestPoints:TP_0.75mm_SMD")
		(at 121.92 207.01 180)
		(unit 1)
		(exclude_from_sim no)
		(in_bom no)
		(on_board yes)
		(dnp no)
		(property "Reference" "TP18"
			(at 115.57 207.01 0)
			(effects
				(font
					(size 1.27 1.27)
				)
			)
		)
		(property "Value" "TP_0.75mm_SMD"
			(at 111.76 203.2 0)
			(effects
				(font
					(size 1.27 1.27)
					(thickness 0.15)
				)
				(justify left bottom)
				(hide yes)
			)
		)
		(property "Footprint" "antmicro-footprints:TP_SMD_0.75mm"
			(at 111.76 200.66 0)
			(effects
				(font
					(size 1.27 1.27)
					(thickness 0.15)
				)
				(justify left bottom)
				(hide yes)
			)
		)
		(property "Datasheet" ""
			(at 104.14 194.31 0)
			(effects
				(font
					(size 1.27 1.27)
					(thickness 0.15)
				)
				(justify left bottom)
				(hide yes)
			)
		)
		(property "Description" "SMT test point"
			(at 121.92 207.01 0)
			(effects
				(font
					(size 1.27 1.27)
				)
				(hide yes)
			)
		)
		(property "MPN" ""
			(at 111.125 195.58 0)
			(effects
				(font
					(size 1.27 1.27)
					(thickness 0.15)
				)
				(justify left bottom)
				(hide yes)
			)
		)
		(property "Manufacturer" ""
			(at 111.125 200.66 0)
			(effects
				(font
					(size 1.27 1.27)
					(thickness 0.15)
				)
				(justify left bottom)
				(hide yes)
			)
		)
		(property "Author" "Antmicro"
			(at 111.76 198.12 0)
			(effects
				(font
					(size 1.27 1.27)
					(thickness 0.15)
				)
				(justify left bottom)
				(hide yes)
			)
		)
		(property "License" "Apache-2.0"
			(at 111.76 195.58 0)
			(effects
				(font
					(size 1.27 1.27)
					(thickness 0.15)
				)
				(justify left bottom)
				(hide yes)
			)
		)
		(pin "1"
		)
		(instances
			(project "jetson-agx-thor-baseboard"
				(path ""
					(reference "TP18")
					(unit 1)
				)
			)
		)
	)
	(symbol
		(lib_id "antmicroResistors0402:R_1k_0402")
		(at 179.07 191.77 0)
		(unit 1)
		(exclude_from_sim no)
		(in_bom no)
		(on_board yes)
		(dnp yes)
		(property "Reference" "R134"
			(at 184.785 191.135 0)
			(effects
				(font
					(size 1.27 1.27)
				)
				(justify left bottom)
			)
		)
		(property "Value" "R_1k_0402"
			(at 199.39 204.47 0)
			(effects
				(font
					(size 1.27 1.27)
					(thickness 0.15)
				)
				(justify left bottom)
				(hide yes)
			)
		)
		(property "Footprint" "antmicro-footprints:R_0402_1005Metric"
			(at 199.39 207.01 0)
			(effects
				(font
					(size 1.27 1.27)
					(thickness 0.15)
				)
				(justify left bottom)
				(hide yes)
			)
		)
		(property "Datasheet" "https://www.bourns.com/docs/product-datasheets/cr.pdf"
			(at 199.39 209.55 0)
			(effects
				(font
					(size 1.27 1.27)
					(thickness 0.15)
				)
				(justify left bottom)
				(hide yes)
			)
		)
		(property "Description" "SMD Chip Resistor, 1 kohm, ± 1%, 63 mW, 0402 [1005 Metric], Thick Film, General Purpose"
			(at 179.07 191.77 0)
			(effects
				(font
					(size 1.27 1.27)
				)
				(hide yes)
			)
		)
		(property "Manufacturer" "Bourns"
			(at 199.39 214.63 0)
			(effects
				(font
					(size 1.27 1.27)
					(thickness 0.15)
				)
				(justify left bottom)
				(hide yes)
			)
		)
		(property "MPN" "CR0402-FX-1001GLF"
			(at 199.39 212.09 0)
			(effects
				(font
					(size 1.27 1.27)
					(thickness 0.15)
				)
				(justify left bottom)
				(hide yes)
			)
		)
		(property "Val" "1k"
			(at 176.53 191.135 0)
			(effects
				(font
					(size 1.27 1.27)
					(thickness 0.15)
				)
				(justify left bottom)
			)
		)
		(property "License" "Apache-2.0"
			(at 199.39 217.17 0)
			(effects
				(font
					(size 1.27 1.27)
					(thickness 0.15)
				)
				(justify left bottom)
				(hide yes)
			)
		)
		(property "Author" "Antmicro"
			(at 199.39 219.71 0)
			(effects
				(font
					(size 1.27 1.27)
					(thickness 0.15)
				)
				(justify left bottom)
				(hide yes)
			)
		)
		(property "Tolerance" "1%"
			(at 199.39 201.93 0)
			(effects
				(font
					(size 1.27 1.27)
				)
				(justify left bottom)
				(hide yes)
			)
		)
		(pin "1"
		)
		(pin "2"
		)
		(instances
			(project "jetson-agx-thor-baseboard"
				(path ""
					(reference "R134")
					(unit 1)
				)
			)
		)
	)
	(symbol
		(lib_id "antmicropower:GND")
		(at 232.41 74.93 0)
		(mirror y)
		(unit 1)
		(exclude_from_sim no)
		(in_bom yes)
		(on_board yes)
		(dnp no)
		(property "Reference" "#PWR0266"
			(at 232.41 81.28 0)
			(effects
				(font
					(size 1.27 1.27)
				)
				(justify left bottom)
				(hide yes)
			)
		)
		(property "Value" "GND"
			(at 232.41 78.74 0)
			(effects
				(font
					(size 1.27 1.27)
					(thickness 0.15)
				)
			)
		)
		(property "Footprint" ""
			(at 223.52 82.55 0)
			(effects
				(font
					(size 1.27 1.27)
					(thickness 0.15)
				)
				(justify left bottom)
				(hide yes)
			)
		)
		(property "Datasheet" ""
			(at 223.52 87.63 0)
			(effects
				(font
					(size 1.27 1.27)
					(thickness 0.15)
				)
				(justify left bottom)
				(hide yes)
			)
		)
		(property "Description" ""
			(at 232.41 74.93 0)
			(effects
				(font
					(size 1.27 1.27)
				)
				(hide yes)
			)
		)
		(property "Author" "Antmicro"
			(at 223.52 82.55 0)
			(effects
				(font
					(size 1.27 1.27)
					(thickness 0.15)
				)
				(justify left bottom)
				(hide yes)
			)
		)
		(property "License" "Apache-2.0"
			(at 223.52 85.09 0)
			(effects
				(font
					(size 1.27 1.27)
					(thickness 0.15)
				)
				(justify left bottom)
				(hide yes)
			)
		)
		(pin "1"
		)
		(instances
			(project "jetson-agx-thor-baseboard"
				(path ""
					(reference "#PWR0266")
					(unit 1)
				)
			)
		)
	)
	(symbol
		(lib_id "antmicroCapacitors0402:C_100n_0402")
		(at 99.06 161.29 0)
		(mirror x)
		(unit 1)
		(exclude_from_sim no)
		(in_bom yes)
		(on_board yes)
		(dnp no)
		(property "Reference" "C130"
			(at 105.41 160.02 0)
			(effects
				(font
					(size 1.27 1.27)
				)
			)
		)
		(property "Value" "C_100n_0402"
			(at 119.38 151.13 0)
			(effects
				(font
					(size 1.27 1.27)
					(thickness 0.15)
				)
				(justify left bottom)
				(hide yes)
			)
		)
		(property "Footprint" "antmicro-footprints:C_0402_1005Metric"
			(at 119.38 148.59 0)
			(effects
				(font
					(size 1.27 1.27)
					(thickness 0.15)
				)
				(justify left bottom)
				(hide yes)
			)
		)
		(property "Datasheet" "https://www.murata.com/products/productdetail?partno=GRM155R61H104KE14%23"
			(at 119.38 146.05 0)
			(effects
				(font
					(size 1.27 1.27)
					(thickness 0.15)
				)
				(justify left bottom)
				(hide yes)
			)
		)
		(property "Description" "SMD Multilayer Ceramic Capacitor, 0.1 µF, 50 V, 0402 [1005 Metric], ± 10%, X5R, GRM Series"
			(at 99.06 161.29 0)
			(effects
				(font
					(size 1.27 1.27)
				)
				(hide yes)
			)
		)
		(property "Manufacturer" "Murata"
			(at 119.38 140.97 0)
			(effects
				(font
					(size 1.27 1.27)
					(thickness 0.15)
				)
				(justify left bottom)
				(hide yes)
			)
		)
		(property "MPN" "GRM155R61H104KE14D"
			(at 119.38 143.51 0)
			(effects
				(font
					(size 1.27 1.27)
					(thickness 0.15)
				)
				(justify left bottom)
				(hide yes)
			)
		)
		(property "Val" "100n"
			(at 97.79 162.56 0)
			(effects
				(font
					(size 1.27 1.27)
					(thickness 0.15)
				)
			)
		)
		(property "License" "Apache-2.0"
			(at 119.38 138.43 0)
			(effects
				(font
					(size 1.27 1.27)
					(thickness 0.15)
				)
				(justify left bottom)
				(hide yes)
			)
		)
		(property "Author" "Antmicro"
			(at 119.38 135.89 0)
			(effects
				(font
					(size 1.27 1.27)
					(thickness 0.15)
				)
				(justify left bottom)
				(hide yes)
			)
		)
		(property "Voltage" "50V"
			(at 119.38 133.35 0)
			(effects
				(font
					(size 1.27 1.27)
				)
				(justify left bottom)
				(hide yes)
			)
		)
		(property "Dielectric" "X5R"
			(at 119.38 130.81 0)
			(effects
				(font
					(size 1.27 1.27)
				)
				(justify left bottom)
				(hide yes)
			)
		)
		(pin "1"
		)
		(pin "2"
		)
		(instances
			(project "jetson-agx-thor-baseboard"
				(path ""
					(reference "C130")
					(unit 1)
				)
			)
		)
	)
	(symbol
		(lib_id "antmicropower:GND")
		(at 236.22 173.99 0)
		(mirror y)
		(unit 1)
		(exclude_from_sim no)
		(in_bom yes)
		(on_board yes)
		(dnp no)
		(property "Reference" "#PWR0271"
			(at 236.22 180.34 0)
			(effects
				(font
					(size 1.27 1.27)
				)
				(justify left bottom)
				(hide yes)
			)
		)
		(property "Value" "GND"
			(at 236.22 177.8 0)
			(effects
				(font
					(size 1.27 1.27)
					(thickness 0.15)
				)
			)
		)
		(property "Footprint" ""
			(at 227.33 181.61 0)
			(effects
				(font
					(size 1.27 1.27)
					(thickness 0.15)
				)
				(justify left bottom)
				(hide yes)
			)
		)
		(property "Datasheet" ""
			(at 227.33 186.69 0)
			(effects
				(font
					(size 1.27 1.27)
					(thickness 0.15)
				)
				(justify left bottom)
				(hide yes)
			)
		)
		(property "Description" ""
			(at 236.22 173.99 0)
			(effects
				(font
					(size 1.27 1.27)
				)
				(hide yes)
			)
		)
		(property "Author" "Antmicro"
			(at 227.33 181.61 0)
			(effects
				(font
					(size 1.27 1.27)
					(thickness 0.15)
				)
				(justify left bottom)
				(hide yes)
			)
		)
		(property "License" "Apache-2.0"
			(at 227.33 184.15 0)
			(effects
				(font
					(size 1.27 1.27)
					(thickness 0.15)
				)
				(justify left bottom)
				(hide yes)
			)
		)
		(pin "1"
		)
		(instances
			(project "jetson-agx-thor-baseboard"
				(path ""
					(reference "#PWR0271")
					(unit 1)
				)
			)
		)
	)
	(symbol
		(lib_id "antmicropower:GND")
		(at 261.62 173.99 0)
		(mirror y)
		(unit 1)
		(exclude_from_sim no)
		(in_bom yes)
		(on_board yes)
		(dnp no)
		(property "Reference" "#PWR0279"
			(at 261.62 180.34 0)
			(effects
				(font
					(size 1.27 1.27)
				)
				(justify left bottom)
				(hide yes)
			)
		)
		(property "Value" "GND"
			(at 261.62 177.8 0)
			(effects
				(font
					(size 1.27 1.27)
					(thickness 0.15)
				)
			)
		)
		(property "Footprint" ""
			(at 252.73 181.61 0)
			(effects
				(font
					(size 1.27 1.27)
					(thickness 0.15)
				)
				(justify left bottom)
				(hide yes)
			)
		)
		(property "Datasheet" ""
			(at 252.73 186.69 0)
			(effects
				(font
					(size 1.27 1.27)
					(thickness 0.15)
				)
				(justify left bottom)
				(hide yes)
			)
		)
		(property "Description" ""
			(at 261.62 173.99 0)
			(effects
				(font
					(size 1.27 1.27)
				)
				(hide yes)
			)
		)
		(property "Author" "Antmicro"
			(at 252.73 181.61 0)
			(effects
				(font
					(size 1.27 1.27)
					(thickness 0.15)
				)
				(justify left bottom)
				(hide yes)
			)
		)
		(property "License" "Apache-2.0"
			(at 252.73 184.15 0)
			(effects
				(font
					(size 1.27 1.27)
					(thickness 0.15)
				)
				(justify left bottom)
				(hide yes)
			)
		)
		(pin "1"
		)
		(instances
			(project "jetson-agx-thor-baseboard"
				(path ""
					(reference "#PWR0279")
					(unit 1)
				)
			)
		)
	)
	(symbol
		(lib_id "antmicroCapacitors0402:C_100n_0402")
		(at 276.86 64.77 90)
		(mirror x)
		(unit 1)
		(exclude_from_sim no)
		(in_bom yes)
		(on_board yes)
		(dnp no)
		(property "Reference" "C153"
			(at 278.765 66.04 90)
			(effects
				(font
					(size 1.27 1.27)
				)
				(justify right)
			)
		)
		(property "Value" "C_100n_0402"
			(at 287.02 85.09 0)
			(effects
				(font
					(size 1.27 1.27)
					(thickness 0.15)
				)
				(justify left bottom)
				(hide yes)
			)
		)
		(property "Footprint" "antmicro-footprints:C_0402_1005Metric"
			(at 289.56 85.09 0)
			(effects
				(font
					(size 1.27 1.27)
					(thickness 0.15)
				)
				(justify left bottom)
				(hide yes)
			)
		)
		(property "Datasheet" "https://www.murata.com/products/productdetail?partno=GRM155R61H104KE14%23"
			(at 292.1 85.09 0)
			(effects
				(font
					(size 1.27 1.27)
					(thickness 0.15)
				)
				(justify left bottom)
				(hide yes)
			)
		)
		(property "Description" "SMD Multilayer Ceramic Capacitor, 0.1 µF, 50 V, 0402 [1005 Metric], ± 10%, X5R, GRM Series"
			(at 276.86 64.77 0)
			(effects
				(font
					(size 1.27 1.27)
				)
				(hide yes)
			)
		)
		(property "MPN" "GRM155R61H104KE14D"
			(at 294.64 85.09 0)
			(effects
				(font
					(size 1.27 1.27)
					(thickness 0.15)
				)
				(justify left bottom)
				(hide yes)
			)
		)
		(property "Manufacturer" "Murata"
			(at 297.18 85.09 0)
			(effects
				(font
					(size 1.27 1.27)
					(thickness 0.15)
				)
				(justify left bottom)
				(hide yes)
			)
		)
		(property "Val" "100n"
			(at 278.765 68.58 90)
			(effects
				(font
					(size 1.27 1.27)
					(thickness 0.15)
				)
				(justify right)
			)
		)
		(property "License" "Apache-2.0"
			(at 299.72 85.09 0)
			(effects
				(font
					(size 1.27 1.27)
					(thickness 0.15)
				)
				(justify left bottom)
				(hide yes)
			)
		)
		(property "Author" "Antmicro"
			(at 302.26 85.09 0)
			(effects
				(font
					(size 1.27 1.27)
					(thickness 0.15)
				)
				(justify left bottom)
				(hide yes)
			)
		)
		(property "Voltage" "50V"
			(at 304.8 85.09 0)
			(effects
				(font
					(size 1.27 1.27)
				)
				(justify left bottom)
				(hide yes)
			)
		)
		(property "Dielectric" "X5R"
			(at 307.34 85.09 0)
			(effects
				(font
					(size 1.27 1.27)
				)
				(justify left bottom)
				(hide yes)
			)
		)
		(pin "1"
		)
		(pin "2"
		)
		(instances
			(project "jetson-agx-thor-baseboard"
				(path ""
					(reference "C153")
					(unit 1)
				)
			)
		)
	)
	(symbol
		(lib_id "antmicroTVSDiodes:TPD4E05U06QDQARQ1")
		(at 252.73 172.72 270)
		(unit 1)
		(exclude_from_sim no)
		(in_bom yes)
		(on_board yes)
		(dnp no)
		(fields_autoplaced yes)
		(property "Reference" "U37"
			(at 248.285 184.15 90)
			(effects
				(font
					(size 1.27 1.27)
				)
			)
		)
		(property "Value" "TPD4E05U06QDQARQ1"
			(at 242.57 196.85 0)
			(effects
				(font
					(size 1.27 1.27)
					(thickness 0.15)
				)
				(justify left bottom)
				(hide yes)
			)
		)
		(property "Footprint" "antmicro-footprints:USON-10_2.5x1mm_P0.5mm"
			(at 247.65 196.85 0)
			(effects
				(font
					(size 1.27 1.27)
					(thickness 0.15)
				)
				(justify left bottom)
				(hide yes)
			)
		)
		(property "Datasheet" "https://www.ti.com/lit/ds/symlink/tpd4e05u06-q1.pdf?HQS=dis-mous-null-mousermode-dsf-pf-null-wwe&ts=1663591265741&ref_url=https%253A%252F%252Fwww.mouser.com%252F"
			(at 245.11 196.85 0)
			(effects
				(font
					(size 1.27 1.27)
					(thickness 0.15)
				)
				(justify left bottom)
				(hide yes)
			)
		)
		(property "Description" "TVS diode array, 12 kV, USON-10, 5.5 V, 0.5 pF"
			(at 252.73 172.72 0)
			(effects
				(font
					(size 1.27 1.27)
				)
				(hide yes)
			)
		)
		(property "Manufacturer" "Texas Instruments"
			(at 240.03 196.85 0)
			(effects
				(font
					(size 1.27 1.27)
					(thickness 0.15)
				)
				(justify left bottom)
				(hide yes)
			)
		)
		(property "MPN" "TPD4E05U06QDQARQ1"
			(at 248.285 186.69 90)
			(effects
				(font
					(size 1.27 1.27)
					(thickness 0.15)
				)
			)
		)
		(property "Author" "Antmicro"
			(at 237.49 196.85 0)
			(effects
				(font
					(size 1.27 1.27)
					(thickness 0.15)
				)
				(justify left bottom)
				(hide yes)
			)
		)
		(property "License" "Apache-2.0"
			(at 234.95 196.85 0)
			(effects
				(font
					(size 1.27 1.27)
					(thickness 0.15)
				)
				(justify left bottom)
				(hide yes)
			)
		)
		(pin "1"
		)
		(pin "10"
		)
		(pin "2"
		)
		(pin "3"
		)
		(pin "4"
		)
		(pin "5"
		)
		(pin "6"
		)
		(pin "7"
		)
		(pin "8"
		)
		(pin "9"
		)
		(instances
			(project "jetson-agx-thor-baseboard"
				(path ""
					(reference "U37")
					(unit 1)
				)
			)
		)
	)
	(symbol
		(lib_id "antmicropower:GND")
		(at 204.47 76.2 0)
		(mirror y)
		(unit 1)
		(exclude_from_sim no)
		(in_bom yes)
		(on_board yes)
		(dnp no)
		(property "Reference" "#PWR0259"
			(at 204.47 82.55 0)
			(effects
				(font
					(size 1.27 1.27)
				)
				(justify left bottom)
				(hide yes)
			)
		)
		(property "Value" "GND"
			(at 204.47 80.01 0)
			(effects
				(font
					(size 1.27 1.27)
					(thickness 0.15)
				)
			)
		)
		(property "Footprint" ""
			(at 195.58 83.82 0)
			(effects
				(font
					(size 1.27 1.27)
					(thickness 0.15)
				)
				(justify left bottom)
				(hide yes)
			)
		)
		(property "Datasheet" ""
			(at 195.58 88.9 0)
			(effects
				(font
					(size 1.27 1.27)
					(thickness 0.15)
				)
				(justify left bottom)
				(hide yes)
			)
		)
		(property "Description" ""
			(at 204.47 76.2 0)
			(effects
				(font
					(size 1.27 1.27)
				)
				(hide yes)
			)
		)
		(property "Author" "Antmicro"
			(at 195.58 83.82 0)
			(effects
				(font
					(size 1.27 1.27)
					(thickness 0.15)
				)
				(justify left bottom)
				(hide yes)
			)
		)
		(property "License" "Apache-2.0"
			(at 195.58 86.36 0)
			(effects
				(font
					(size 1.27 1.27)
					(thickness 0.15)
				)
				(justify left bottom)
				(hide yes)
			)
		)
		(pin "1"
		)
		(instances
			(project "jetson-agx-thor-baseboard"
				(path ""
					(reference "#PWR0259")
					(unit 1)
				)
			)
		)
	)
	(symbol
		(lib_id "antmicroResistors0402:R_100k_0402")
		(at 90.17 187.96 270)
		(unit 1)
		(exclude_from_sim no)
		(in_bom yes)
		(on_board yes)
		(dnp no)
		(fields_autoplaced yes)
		(property "Reference" "R117"
			(at 92.71 189.23 90)
			(effects
				(font
					(size 1.27 1.27)
				)
				(justify left)
			)
		)
		(property "Value" "R_100k_0402"
			(at 77.47 208.28 0)
			(effects
				(font
					(size 1.27 1.27)
					(thickness 0.15)
				)
				(justify left bottom)
				(hide yes)
			)
		)
		(property "Footprint" "antmicro-footprints:R_0402_1005Metric"
			(at 74.93 208.28 0)
			(effects
				(font
					(size 1.27 1.27)
					(thickness 0.15)
				)
				(justify left bottom)
				(hide yes)
			)
		)
		(property "Datasheet" "https://www.bourns.com/docs/product-datasheets/cr.pdf"
			(at 72.39 208.28 0)
			(effects
				(font
					(size 1.27 1.27)
					(thickness 0.15)
				)
				(justify left bottom)
				(hide yes)
			)
		)
		(property "Description" "SMD Chip Resistor, 100 kohm, ± 1%, 62.5 mW, 0402 [1005 Metric], Thick Film, General Purpose"
			(at 90.17 187.96 0)
			(effects
				(font
					(size 1.27 1.27)
				)
				(hide yes)
			)
		)
		(property "Manufacturer" "Bourns"
			(at 67.31 208.28 0)
			(effects
				(font
					(size 1.27 1.27)
					(thickness 0.15)
				)
				(justify left bottom)
				(hide yes)
			)
		)
		(property "MPN" "CR0402-FX-1003GLF"
			(at 69.85 208.28 0)
			(effects
				(font
					(size 1.27 1.27)
					(thickness 0.15)
				)
				(justify left bottom)
				(hide yes)
			)
		)
		(property "Val" "100k"
			(at 92.71 191.77 90)
			(effects
				(font
					(size 1.27 1.27)
					(thickness 0.15)
				)
				(justify left)
			)
		)
		(property "License" "Apache-2.0"
			(at 64.77 208.28 0)
			(effects
				(font
					(size 1.27 1.27)
					(thickness 0.15)
				)
				(justify left bottom)
				(hide yes)
			)
		)
		(property "Author" "Antmicro"
			(at 62.23 208.28 0)
			(effects
				(font
					(size 1.27 1.27)
					(thickness 0.15)
				)
				(justify left bottom)
				(hide yes)
			)
		)
		(property "Tolerance" "1%"
			(at 80.01 208.28 0)
			(effects
				(font
					(size 1.27 1.27)
				)
				(justify left bottom)
				(hide yes)
			)
		)
		(pin "1"
		)
		(pin "2"
		)
		(instances
			(project "jetson-agx-thor-baseboard"
				(path ""
					(reference "R117")
					(unit 1)
				)
			)
		)
	)
	(symbol
		(lib_id "antmicroResistors0402:R_1k_0402")
		(at 179.07 196.85 0)
		(unit 1)
		(exclude_from_sim no)
		(in_bom no)
		(on_board yes)
		(dnp yes)
		(property "Reference" "R136"
			(at 184.785 196.215 0)
			(effects
				(font
					(size 1.27 1.27)
				)
				(justify left bottom)
			)
		)
		(property "Value" "R_1k_0402"
			(at 199.39 209.55 0)
			(effects
				(font
					(size 1.27 1.27)
					(thickness 0.15)
				)
				(justify left bottom)
				(hide yes)
			)
		)
		(property "Footprint" "antmicro-footprints:R_0402_1005Metric"
			(at 199.39 212.09 0)
			(effects
				(font
					(size 1.27 1.27)
					(thickness 0.15)
				)
				(justify left bottom)
				(hide yes)
			)
		)
		(property "Datasheet" "https://www.bourns.com/docs/product-datasheets/cr.pdf"
			(at 199.39 214.63 0)
			(effects
				(font
					(size 1.27 1.27)
					(thickness 0.15)
				)
				(justify left bottom)
				(hide yes)
			)
		)
		(property "Description" "SMD Chip Resistor, 1 kohm, ± 1%, 63 mW, 0402 [1005 Metric], Thick Film, General Purpose"
			(at 179.07 196.85 0)
			(effects
				(font
					(size 1.27 1.27)
				)
				(hide yes)
			)
		)
		(property "Manufacturer" "Bourns"
			(at 199.39 219.71 0)
			(effects
				(font
					(size 1.27 1.27)
					(thickness 0.15)
				)
				(justify left bottom)
				(hide yes)
			)
		)
		(property "MPN" "CR0402-FX-1001GLF"
			(at 199.39 217.17 0)
			(effects
				(font
					(size 1.27 1.27)
					(thickness 0.15)
				)
				(justify left bottom)
				(hide yes)
			)
		)
		(property "Val" "1k"
			(at 176.53 196.215 0)
			(effects
				(font
					(size 1.27 1.27)
					(thickness 0.15)
				)
				(justify left bottom)
			)
		)
		(property "License" "Apache-2.0"
			(at 199.39 222.25 0)
			(effects
				(font
					(size 1.27 1.27)
					(thickness 0.15)
				)
				(justify left bottom)
				(hide yes)
			)
		)
		(property "Author" "Antmicro"
			(at 199.39 224.79 0)
			(effects
				(font
					(size 1.27 1.27)
					(thickness 0.15)
				)
				(justify left bottom)
				(hide yes)
			)
		)
		(property "Tolerance" "1%"
			(at 199.39 207.01 0)
			(effects
				(font
					(size 1.27 1.27)
				)
				(justify left bottom)
				(hide yes)
			)
		)
		(pin "1"
		)
		(pin "2"
		)
		(instances
			(project "jetson-agx-thor-baseboard"
				(path ""
					(reference "R136")
					(unit 1)
				)
			)
		)
	)
	(symbol
		(lib_id "antmicropower:+3V3")
		(at 180.34 48.26 0)
		(unit 1)
		(exclude_from_sim no)
		(in_bom yes)
		(on_board yes)
		(dnp no)
		(property "Reference" "#PWR0246"
			(at 180.34 52.07 0)
			(effects
				(font
					(size 1.27 1.27)
				)
				(justify left bottom)
				(hide yes)
			)
		)
		(property "Value" "+3V3"
			(at 177.165 45.085 0)
			(effects
				(font
					(size 1.27 1.27)
					(thickness 0.15)
				)
				(justify left bottom)
			)
		)
		(property "Footprint" ""
			(at 195.58 55.88 0)
			(effects
				(font
					(size 1.27 1.27)
					(thickness 0.15)
				)
				(justify left bottom)
				(hide yes)
			)
		)
		(property "Datasheet" ""
			(at 195.58 58.42 0)
			(effects
				(font
					(size 1.27 1.27)
					(thickness 0.15)
				)
				(justify left bottom)
				(hide yes)
			)
		)
		(property "Description" ""
			(at 180.34 48.26 0)
			(effects
				(font
					(size 1.27 1.27)
				)
				(hide yes)
			)
		)
		(property "Author" "Antmicro"
			(at 195.58 50.8 0)
			(effects
				(font
					(size 1.27 1.27)
					(thickness 0.15)
				)
				(justify left bottom)
				(hide yes)
			)
		)
		(property "License" "Apache-2.0"
			(at 195.58 53.34 0)
			(effects
				(font
					(size 1.27 1.27)
					(thickness 0.15)
				)
				(justify left bottom)
				(hide yes)
			)
		)
		(pin "1"
		)
		(instances
			(project "jetson-agx-thor-baseboard"
				(path ""
					(reference "#PWR0246")
					(unit 1)
				)
			)
		)
	)
	(symbol
		(lib_id "antmicroCapacitors0402:C_100n_0402")
		(at 96.52 151.13 0)
		(mirror x)
		(unit 1)
		(exclude_from_sim no)
		(in_bom yes)
		(on_board yes)
		(dnp no)
		(property "Reference" "C127"
			(at 102.87 149.86 0)
			(effects
				(font
					(size 1.27 1.27)
				)
			)
		)
		(property "Value" "C_100n_0402"
			(at 116.84 140.97 0)
			(effects
				(font
					(size 1.27 1.27)
					(thickness 0.15)
				)
				(justify left bottom)
				(hide yes)
			)
		)
		(property "Footprint" "antmicro-footprints:C_0402_1005Metric"
			(at 116.84 138.43 0)
			(effects
				(font
					(size 1.27 1.27)
					(thickness 0.15)
				)
				(justify left bottom)
				(hide yes)
			)
		)
		(property "Datasheet" "https://www.murata.com/products/productdetail?partno=GRM155R61H104KE14%23"
			(at 116.84 135.89 0)
			(effects
				(font
					(size 1.27 1.27)
					(thickness 0.15)
				)
				(justify left bottom)
				(hide yes)
			)
		)
		(property "Description" "SMD Multilayer Ceramic Capacitor, 0.1 µF, 50 V, 0402 [1005 Metric], ± 10%, X5R, GRM Series"
			(at 96.52 151.13 0)
			(effects
				(font
					(size 1.27 1.27)
				)
				(hide yes)
			)
		)
		(property "Manufacturer" "Murata"
			(at 116.84 130.81 0)
			(effects
				(font
					(size 1.27 1.27)
					(thickness 0.15)
				)
				(justify left bottom)
				(hide yes)
			)
		)
		(property "MPN" "GRM155R61H104KE14D"
			(at 116.84 133.35 0)
			(effects
				(font
					(size 1.27 1.27)
					(thickness 0.15)
				)
				(justify left bottom)
				(hide yes)
			)
		)
		(property "Val" "100n"
			(at 95.25 152.4 0)
			(effects
				(font
					(size 1.27 1.27)
					(thickness 0.15)
				)
			)
		)
		(property "License" "Apache-2.0"
			(at 116.84 128.27 0)
			(effects
				(font
					(size 1.27 1.27)
					(thickness 0.15)
				)
				(justify left bottom)
				(hide yes)
			)
		)
		(property "Author" "Antmicro"
			(at 116.84 125.73 0)
			(effects
				(font
					(size 1.27 1.27)
					(thickness 0.15)
				)
				(justify left bottom)
				(hide yes)
			)
		)
		(property "Voltage" "50V"
			(at 116.84 123.19 0)
			(effects
				(font
					(size 1.27 1.27)
				)
				(justify left bottom)
				(hide yes)
			)
		)
		(property "Dielectric" "X5R"
			(at 116.84 120.65 0)
			(effects
				(font
					(size 1.27 1.27)
				)
				(justify left bottom)
				(hide yes)
			)
		)
		(pin "1"
		)
		(pin "2"
		)
		(instances
			(project "jetson-agx-thor-baseboard"
				(path ""
					(reference "C127")
					(unit 1)
				)
			)
		)
	)
	(symbol
		(lib_id "antmicroTestPoints:TP_0.75mm_SMD")
		(at 259.08 63.5 90)
		(unit 1)
		(exclude_from_sim no)
		(in_bom no)
		(on_board yes)
		(dnp no)
		(fields_autoplaced yes)
		(property "Reference" "TP20"
			(at 261.62 60.3249 90)
			(effects
				(font
					(size 1.27 1.27)
				)
				(justify right)
			)
		)
		(property "Value" "TP_0.75mm_SMD"
			(at 262.89 53.34 0)
			(effects
				(font
					(size 1.27 1.27)
					(thickness 0.15)
				)
				(justify left bottom)
				(hide yes)
			)
		)
		(property "Footprint" "antmicro-footprints:TP_SMD_0.75mm"
			(at 265.43 53.34 0)
			(effects
				(font
					(size 1.27 1.27)
					(thickness 0.15)
				)
				(justify left bottom)
				(hide yes)
			)
		)
		(property "Datasheet" ""
			(at 271.78 45.72 0)
			(effects
				(font
					(size 1.27 1.27)
					(thickness 0.15)
				)
				(justify left bottom)
				(hide yes)
			)
		)
		(property "Description" "SMT test point"
			(at 259.08 63.5 0)
			(effects
				(font
					(size 1.27 1.27)
				)
				(hide yes)
			)
		)
		(property "MPN" ""
			(at 270.51 52.705 0)
			(effects
				(font
					(size 1.27 1.27)
					(thickness 0.15)
				)
				(justify left bottom)
				(hide yes)
			)
		)
		(property "Manufacturer" ""
			(at 265.43 52.705 0)
			(effects
				(font
					(size 1.27 1.27)
					(thickness 0.15)
				)
				(justify left bottom)
				(hide yes)
			)
		)
		(property "Author" "Antmicro"
			(at 267.97 53.34 0)
			(effects
				(font
					(size 1.27 1.27)
					(thickness 0.15)
				)
				(justify left bottom)
				(hide yes)
			)
		)
		(property "License" "Apache-2.0"
			(at 270.51 53.34 0)
			(effects
				(font
					(size 1.27 1.27)
					(thickness 0.15)
				)
				(justify left bottom)
				(hide yes)
			)
		)
		(pin "1"
		)
		(instances
			(project "jetson-agx-thor-baseboard"
				(path ""
					(reference "TP20")
					(unit 1)
				)
			)
		)
	)
	(symbol
		(lib_id "antmicropower:GND")
		(at 90.17 194.31 0)
		(mirror y)
		(unit 1)
		(exclude_from_sim no)
		(in_bom yes)
		(on_board yes)
		(dnp no)
		(property "Reference" "#PWR0240"
			(at 90.17 200.66 0)
			(effects
				(font
					(size 1.27 1.27)
				)
				(justify left bottom)
				(hide yes)
			)
		)
		(property "Value" "GND"
			(at 90.17 198.12 0)
			(effects
				(font
					(size 1.27 1.27)
					(thickness 0.15)
				)
			)
		)
		(property "Footprint" ""
			(at 81.28 201.93 0)
			(effects
				(font
					(size 1.27 1.27)
					(thickness 0.15)
				)
				(justify left bottom)
				(hide yes)
			)
		)
		(property "Datasheet" ""
			(at 81.28 207.01 0)
			(effects
				(font
					(size 1.27 1.27)
					(thickness 0.15)
				)
				(justify left bottom)
				(hide yes)
			)
		)
		(property "Description" ""
			(at 90.17 194.31 0)
			(effects
				(font
					(size 1.27 1.27)
				)
				(hide yes)
			)
		)
		(property "Author" "Antmicro"
			(at 81.28 201.93 0)
			(effects
				(font
					(size 1.27 1.27)
					(thickness 0.15)
				)
				(justify left bottom)
				(hide yes)
			)
		)
		(property "License" "Apache-2.0"
			(at 81.28 204.47 0)
			(effects
				(font
					(size 1.27 1.27)
					(thickness 0.15)
				)
				(justify left bottom)
				(hide yes)
			)
		)
		(pin "1"
		)
		(instances
			(project "jetson-agx-thor-baseboard"
				(path ""
					(reference "#PWR0240")
					(unit 1)
				)
			)
		)
	)
	(symbol
		(lib_id "antmicroTransistorsFETsMOSFETsSingle:DMG1012T-7")
		(at 137.16 237.49 0)
		(unit 1)
		(exclude_from_sim no)
		(in_bom yes)
		(on_board yes)
		(dnp no)
		(fields_autoplaced yes)
		(property "Reference" "Q35"
			(at 147.32 233.68 0)
			(effects
				(font
					(size 1.27 1.27)
					(thickness 0.15)
				)
				(justify left)
			)
		)
		(property "Value" "DMG1012T-7"
			(at 147.32 241.3 0)
			(effects
				(font
					(size 1.27 1.27)
					(thickness 0.15)
				)
				(justify left bottom)
				(hide yes)
			)
		)
		(property "Footprint" "antmicro-footprints:SOT-523"
			(at 147.32 243.84 0)
			(effects
				(font
					(size 1.27 1.27)
					(thickness 0.15)
				)
				(justify left bottom)
				(hide yes)
			)
		)
		(property "Datasheet" "https://www.diodes.com/assets/Datasheets/ds31783.pdf"
			(at 147.32 246.38 0)
			(effects
				(font
					(size 1.27 1.27)
					(thickness 0.15)
				)
				(justify left bottom)
				(hide yes)
			)
		)
		(property "Description" "Power MOSFET, N Channel, 20 V, 630 mA, 0.3 ohm, SOT-523, Surface Mount"
			(at 147.32 254 0)
			(effects
				(font
					(size 1.27 1.27)
				)
				(justify left bottom)
				(hide yes)
			)
		)
		(property "MPN" "DMG1012T-7"
			(at 147.32 236.22 0)
			(effects
				(font
					(size 1.27 1.27)
					(thickness 0.15)
				)
				(justify left)
			)
		)
		(property "Manufacturer" "Diodes Incorporated"
			(at 147.32 238.76 0)
			(effects
				(font
					(size 1.27 1.27)
					(thickness 0.15)
				)
				(justify left bottom)
				(hide yes)
			)
		)
		(property "Author" "Antmicro"
			(at 147.32 248.92 0)
			(effects
				(font
					(size 1.27 1.27)
					(thickness 0.15)
				)
				(justify left bottom)
				(hide yes)
			)
		)
		(property "License" "Apache-2.0"
			(at 147.32 251.46 0)
			(effects
				(font
					(size 1.27 1.27)
					(thickness 0.15)
				)
				(justify left bottom)
				(hide yes)
			)
		)
		(pin "1"
		)
		(pin "3"
		)
		(pin "2"
		)
		(instances
			(project "jetson-agx-thor-baseboard"
				(path ""
					(reference "Q35")
					(unit 1)
				)
			)
		)
	)
	(symbol
		(lib_id "antmicroCapacitors0402:C_100n_0402")
		(at 96.52 158.75 0)
		(mirror x)
		(unit 1)
		(exclude_from_sim no)
		(in_bom yes)
		(on_board yes)
		(dnp no)
		(property "Reference" "C128"
			(at 102.87 157.48 0)
			(effects
				(font
					(size 1.27 1.27)
				)
			)
		)
		(property "Value" "C_100n_0402"
			(at 116.84 148.59 0)
			(effects
				(font
					(size 1.27 1.27)
					(thickness 0.15)
				)
				(justify left bottom)
				(hide yes)
			)
		)
		(property "Footprint" "antmicro-footprints:C_0402_1005Metric"
			(at 116.84 146.05 0)
			(effects
				(font
					(size 1.27 1.27)
					(thickness 0.15)
				)
				(justify left bottom)
				(hide yes)
			)
		)
		(property "Datasheet" "https://www.murata.com/products/productdetail?partno=GRM155R61H104KE14%23"
			(at 116.84 143.51 0)
			(effects
				(font
					(size 1.27 1.27)
					(thickness 0.15)
				)
				(justify left bottom)
				(hide yes)
			)
		)
		(property "Description" "SMD Multilayer Ceramic Capacitor, 0.1 µF, 50 V, 0402 [1005 Metric], ± 10%, X5R, GRM Series"
			(at 96.52 158.75 0)
			(effects
				(font
					(size 1.27 1.27)
				)
				(hide yes)
			)
		)
		(property "Manufacturer" "Murata"
			(at 116.84 138.43 0)
			(effects
				(font
					(size 1.27 1.27)
					(thickness 0.15)
				)
				(justify left bottom)
				(hide yes)
			)
		)
		(property "MPN" "GRM155R61H104KE14D"
			(at 116.84 140.97 0)
			(effects
				(font
					(size 1.27 1.27)
					(thickness 0.15)
				)
				(justify left bottom)
				(hide yes)
			)
		)
		(property "Val" "100n"
			(at 95.25 160.02 0)
			(effects
				(font
					(size 1.27 1.27)
					(thickness 0.15)
				)
			)
		)
		(property "License" "Apache-2.0"
			(at 116.84 135.89 0)
			(effects
				(font
					(size 1.27 1.27)
					(thickness 0.15)
				)
				(justify left bottom)
				(hide yes)
			)
		)
		(property "Author" "Antmicro"
			(at 116.84 133.35 0)
			(effects
				(font
					(size 1.27 1.27)
					(thickness 0.15)
				)
				(justify left bottom)
				(hide yes)
			)
		)
		(property "Voltage" "50V"
			(at 116.84 130.81 0)
			(effects
				(font
					(size 1.27 1.27)
				)
				(justify left bottom)
				(hide yes)
			)
		)
		(property "Dielectric" "X5R"
			(at 116.84 128.27 0)
			(effects
				(font
					(size 1.27 1.27)
				)
				(justify left bottom)
				(hide yes)
			)
		)
		(pin "1"
		)
		(pin "2"
		)
		(instances
			(project "jetson-agx-thor-baseboard"
				(path ""
					(reference "C128")
					(unit 1)
				)
			)
		)
	)
	(symbol
		(lib_id "antmicroInterfaceControllers:TUSB1046-DCIRNQ")
		(at 125.73 135.89 0)
		(unit 1)
		(exclude_from_sim no)
		(in_bom yes)
		(on_board yes)
		(dnp no)
		(property "Reference" "U33"
			(at 137.668 128.524 0)
			(effects
				(font
					(size 1.27 1.27)
				)
			)
		)
		(property "Value" "TUSB1046-DCIRNQ"
			(at 129.032 131.572 0)
			(effects
				(font
					(size 1.27 1.27)
					(thickness 0.15)
				)
				(justify left bottom)
				(hide yes)
			)
		)
		(property "Footprint" "antmicro-footprints:WQFN-40_1EP_6x3mm_Pitch0.4mm_EP4.7x2.7mm"
			(at 163.83 143.51 0)
			(effects
				(font
					(size 1.27 1.27)
					(thickness 0.15)
				)
				(justify left bottom)
				(hide yes)
			)
		)
		(property "Datasheet" "https://www.ti.com/lit/ds/sllsew2d/sllsew2d.pdf?ts=1662107117482&ref_url=https%253A%252F%252Fwww.google.com%252F"
			(at 163.83 146.05 0)
			(effects
				(font
					(size 1.27 1.27)
					(thickness 0.15)
				)
				(justify left bottom)
				(hide yes)
			)
		)
		(property "Description" "Analog & Digital Crosspoint ICs USB Type-C DP ALT Mode, 10-Gbps linear redriver crosspoint switch 40-WQFN 0°C to 70°C"
			(at 125.73 135.89 0)
			(effects
				(font
					(size 1.27 1.27)
				)
				(hide yes)
			)
		)
		(property "MPN" "TUSB1046-DCIRNQT"
			(at 138.176 131.064 0)
			(effects
				(font
					(size 1.27 1.27)
					(thickness 0.15)
				)
			)
		)
		(property "Manufacturer" "Texas Instruments"
			(at 163.83 151.13 0)
			(effects
				(font
					(size 1.27 1.27)
					(thickness 0.15)
				)
				(justify left bottom)
				(hide yes)
			)
		)
		(property "Author" "Antmicro"
			(at 163.83 153.67 0)
			(effects
				(font
					(size 1.27 1.27)
					(thickness 0.15)
				)
				(justify left bottom)
				(hide yes)
			)
		)
		(property "License" "Apache-2.0"
			(at 163.83 156.21 0)
			(effects
				(font
					(size 1.27 1.27)
					(thickness 0.15)
				)
				(justify left bottom)
				(hide yes)
			)
		)
		(pin "1"
		)
		(pin "10"
		)
		(pin "11"
		)
		(pin "12"
		)
		(pin "13"
		)
		(pin "14"
		)
		(pin "15"
		)
		(pin "16"
		)
		(pin "17"
		)
		(pin "18"
		)
		(pin "19"
		)
		(pin "2"
		)
		(pin "20"
		)
		(pin "21"
		)
		(pin "22"
		)
		(pin "23"
		)
		(pin "24"
		)
		(pin "25"
		)
		(pin "26"
		)
		(pin "27"
		)
		(pin "28"
		)
		(pin "29"
		)
		(pin "3"
		)
		(pin "30"
		)
		(pin "31"
		)
		(pin "32"
		)
		(pin "33"
		)
		(pin "34"
		)
		(pin "35"
		)
		(pin "36"
		)
		(pin "37"
		)
		(pin "38"
		)
		(pin "39"
		)
		(pin "4"
		)
		(pin "40"
		)
		(pin "41"
		)
		(pin "5"
		)
		(pin "6"
		)
		(pin "7"
		)
		(pin "8"
		)
		(pin "9"
		)
		(instances
			(project "jetson-agx-thor-baseboard"
				(path ""
					(reference "U33")
					(unit 1)
				)
			)
		)
	)
	(symbol
		(lib_id "antmicroTestPoints:TP_0.75mm_SMD")
		(at 105.41 208.28 90)
		(unit 1)
		(exclude_from_sim no)
		(in_bom no)
		(on_board yes)
		(dnp no)
		(property "Reference" "TP17"
			(at 107.95 203.2 90)
			(effects
				(font
					(size 1.27 1.27)
				)
				(justify left)
			)
		)
		(property "Value" "TP_0.75mm_SMD"
			(at 109.22 198.12 0)
			(effects
				(font
					(size 1.27 1.27)
					(thickness 0.15)
				)
				(justify left bottom)
				(hide yes)
			)
		)
		(property "Footprint" "antmicro-footprints:TP_SMD_0.75mm"
			(at 111.76 198.12 0)
			(effects
				(font
					(size 1.27 1.27)
					(thickness 0.15)
				)
				(justify left bottom)
				(hide yes)
			)
		)
		(property "Datasheet" ""
			(at 118.11 190.5 0)
			(effects
				(font
					(size 1.27 1.27)
					(thickness 0.15)
				)
				(justify left bottom)
				(hide yes)
			)
		)
		(property "Description" "SMT test point"
			(at 105.41 208.28 0)
			(effects
				(font
					(size 1.27 1.27)
				)
				(hide yes)
			)
		)
		(property "MPN" ""
			(at 116.84 197.485 0)
			(effects
				(font
					(size 1.27 1.27)
					(thickness 0.15)
				)
				(justify left bottom)
				(hide yes)
			)
		)
		(property "Manufacturer" ""
			(at 111.76 197.485 0)
			(effects
				(font
					(size 1.27 1.27)
					(thickness 0.15)
				)
				(justify left bottom)
				(hide yes)
			)
		)
		(property "Author" "Antmicro"
			(at 114.3 198.12 0)
			(effects
				(font
					(size 1.27 1.27)
					(thickness 0.15)
				)
				(justify left bottom)
				(hide yes)
			)
		)
		(property "License" "Apache-2.0"
			(at 116.84 198.12 0)
			(effects
				(font
					(size 1.27 1.27)
					(thickness 0.15)
				)
				(justify left bottom)
				(hide yes)
			)
		)
		(pin "1"
		)
		(instances
			(project "jetson-agx-thor-baseboard"
				(path ""
					(reference "TP17")
					(unit 1)
				)
			)
		)
	)
	(symbol
		(lib_id "antmicroResistors0402:R_1k_0402")
		(at 179.07 179.07 0)
		(unit 1)
		(exclude_from_sim no)
		(in_bom yes)
		(on_board yes)
		(dnp no)
		(property "Reference" "R129"
			(at 184.785 178.435 0)
			(effects
				(font
					(size 1.27 1.27)
				)
				(justify left bottom)
			)
		)
		(property "Value" "R_1k_0402"
			(at 199.39 191.77 0)
			(effects
				(font
					(size 1.27 1.27)
					(thickness 0.15)
				)
				(justify left bottom)
				(hide yes)
			)
		)
		(property "Footprint" "antmicro-footprints:R_0402_1005Metric"
			(at 199.39 194.31 0)
			(effects
				(font
					(size 1.27 1.27)
					(thickness 0.15)
				)
				(justify left bottom)
				(hide yes)
			)
		)
		(property "Datasheet" "https://www.bourns.com/docs/product-datasheets/cr.pdf"
			(at 199.39 196.85 0)
			(effects
				(font
					(size 1.27 1.27)
					(thickness 0.15)
				)
				(justify left bottom)
				(hide yes)
			)
		)
		(property "Description" "SMD Chip Resistor, 1 kohm, ± 1%, 63 mW, 0402 [1005 Metric], Thick Film, General Purpose"
			(at 179.07 179.07 0)
			(effects
				(font
					(size 1.27 1.27)
				)
				(hide yes)
			)
		)
		(property "Manufacturer" "Bourns"
			(at 199.39 201.93 0)
			(effects
				(font
					(size 1.27 1.27)
					(thickness 0.15)
				)
				(justify left bottom)
				(hide yes)
			)
		)
		(property "MPN" "CR0402-FX-1001GLF"
			(at 199.39 199.39 0)
			(effects
				(font
					(size 1.27 1.27)
					(thickness 0.15)
				)
				(justify left bottom)
				(hide yes)
			)
		)
		(property "Val" "1k"
			(at 176.53 178.435 0)
			(effects
				(font
					(size 1.27 1.27)
					(thickness 0.15)
				)
				(justify left bottom)
			)
		)
		(property "License" "Apache-2.0"
			(at 199.39 204.47 0)
			(effects
				(font
					(size 1.27 1.27)
					(thickness 0.15)
				)
				(justify left bottom)
				(hide yes)
			)
		)
		(property "Author" "Antmicro"
			(at 199.39 207.01 0)
			(effects
				(font
					(size 1.27 1.27)
					(thickness 0.15)
				)
				(justify left bottom)
				(hide yes)
			)
		)
		(property "Tolerance" "1%"
			(at 199.39 189.23 0)
			(effects
				(font
					(size 1.27 1.27)
				)
				(justify left bottom)
				(hide yes)
			)
		)
		(pin "1"
		)
		(pin "2"
		)
		(instances
			(project "jetson-agx-thor-baseboard"
				(path ""
					(reference "R129")
					(unit 1)
				)
			)
		)
	)
	(symbol
		(lib_id "antmicroCapacitors0402:C_100n_0402")
		(at 83.82 104.14 90)
		(mirror x)
		(unit 1)
		(exclude_from_sim no)
		(in_bom yes)
		(on_board yes)
		(dnp no)
		(property "Reference" "C125"
			(at 85.725 105.41 90)
			(effects
				(font
					(size 1.27 1.27)
				)
				(justify right)
			)
		)
		(property "Value" "C_100n_0402"
			(at 93.98 124.46 0)
			(effects
				(font
					(size 1.27 1.27)
					(thickness 0.15)
				)
				(justify left bottom)
				(hide yes)
			)
		)
		(property "Footprint" "antmicro-footprints:C_0402_1005Metric"
			(at 96.52 124.46 0)
			(effects
				(font
					(size 1.27 1.27)
					(thickness 0.15)
				)
				(justify left bottom)
				(hide yes)
			)
		)
		(property "Datasheet" "https://www.murata.com/products/productdetail?partno=GRM155R61H104KE14%23"
			(at 99.06 124.46 0)
			(effects
				(font
					(size 1.27 1.27)
					(thickness 0.15)
				)
				(justify left bottom)
				(hide yes)
			)
		)
		(property "Description" "SMD Multilayer Ceramic Capacitor, 0.1 µF, 50 V, 0402 [1005 Metric], ± 10%, X5R, GRM Series"
			(at 83.82 104.14 0)
			(effects
				(font
					(size 1.27 1.27)
				)
				(hide yes)
			)
		)
		(property "Manufacturer" "Murata"
			(at 104.14 124.46 0)
			(effects
				(font
					(size 1.27 1.27)
					(thickness 0.15)
				)
				(justify left bottom)
				(hide yes)
			)
		)
		(property "MPN" "GRM155R61H104KE14D"
			(at 101.6 124.46 0)
			(effects
				(font
					(size 1.27 1.27)
					(thickness 0.15)
				)
				(justify left bottom)
				(hide yes)
			)
		)
		(property "Val" "100n"
			(at 85.725 107.95 90)
			(effects
				(font
					(size 1.27 1.27)
					(thickness 0.15)
				)
				(justify right)
			)
		)
		(property "License" "Apache-2.0"
			(at 106.68 124.46 0)
			(effects
				(font
					(size 1.27 1.27)
					(thickness 0.15)
				)
				(justify left bottom)
				(hide yes)
			)
		)
		(property "Author" "Antmicro"
			(at 109.22 124.46 0)
			(effects
				(font
					(size 1.27 1.27)
					(thickness 0.15)
				)
				(justify left bottom)
				(hide yes)
			)
		)
		(property "Voltage" "50V"
			(at 111.76 124.46 0)
			(effects
				(font
					(size 1.27 1.27)
				)
				(justify left bottom)
				(hide yes)
			)
		)
		(property "Dielectric" "X5R"
			(at 114.3 124.46 0)
			(effects
				(font
					(size 1.27 1.27)
				)
				(justify left bottom)
				(hide yes)
			)
		)
		(pin "1"
		)
		(pin "2"
		)
		(instances
			(project "jetson-agx-thor-baseboard"
				(path ""
					(reference "C125")
					(unit 1)
				)
			)
		)
	)
	(symbol
		(lib_id "antmicroUSBConnectors:USB-C_Kycon_KUSBX-SL2-CS1N24-B-TR")
		(at 306.07 110.49 0)
		(mirror y)
		(unit 1)
		(exclude_from_sim no)
		(in_bom yes)
		(on_board yes)
		(dnp no)
		(property "Reference" "J9"
			(at 319.405 102.87 0)
			(effects
				(font
					(size 1.27 1.27)
					(thickness 0.15)
				)
			)
		)
		(property "Value" "USB-C_Kycon_KUSBX-SL2-CS1N24-B-TR"
			(at 262.89 115.57 0)
			(effects
				(font
					(size 1.27 1.27)
					(thickness 0.15)
				)
				(justify left bottom)
				(hide yes)
			)
		)
		(property "Footprint" "antmicro-footprints:USB-C_Receptacle_Kycon_KUSBX-SL2-CS1N24-B-TR"
			(at 262.89 118.11 0)
			(effects
				(font
					(size 1.27 1.27)
					(thickness 0.15)
				)
				(justify left bottom)
				(hide yes)
			)
		)
		(property "Datasheet" "https://www.kycon.com/Pub_Eng_Draw/KUSBX-SL2-CS1N24-B-TR.pdf"
			(at 262.89 120.65 0)
			(effects
				(font
					(size 1.27 1.27)
					(thickness 0.15)
				)
				(justify left bottom)
				(hide yes)
			)
		)
		(property "Description" "USB-C (USB TYPE-C) USB 3.2 Gen 2 (USB 3.1 Gen 2, Superspeed + (USB 3.1)) USB PD Receptacle Connector 24 Position Surface Mount"
			(at 262.89 133.35 0)
			(effects
				(font
					(size 1.27 1.27)
				)
				(justify left bottom)
				(hide yes)
			)
		)
		(property "MPN" "KUSBX-SL2-CS1N24-B-TR"
			(at 319.405 105.41 0)
			(effects
				(font
					(size 1.27 1.27)
					(thickness 0.15)
				)
			)
		)
		(property "Manufacturer" "Kycon"
			(at 262.89 125.73 0)
			(effects
				(font
					(size 1.27 1.27)
					(thickness 0.15)
				)
				(justify left bottom)
				(hide yes)
			)
		)
		(property "License" "Apache-2.0"
			(at 262.89 128.27 0)
			(effects
				(font
					(size 1.27 1.27)
					(thickness 0.15)
				)
				(justify left bottom)
				(hide yes)
			)
		)
		(property "Author" "Antmicro"
			(at 262.89 130.81 0)
			(effects
				(font
					(size 1.27 1.27)
					(thickness 0.15)
				)
				(justify left bottom)
				(hide yes)
			)
		)
		(pin "A6"
		)
		(pin "A2"
		)
		(pin "SH"
		)
		(pin "A1"
		)
		(pin "B12"
		)
		(pin "B7"
		)
		(pin "A12"
		)
		(pin "A8"
		)
		(pin "B1"
		)
		(pin "B8"
		)
		(pin "A3"
		)
		(pin "B10"
		)
		(pin "B3"
		)
		(pin "A7"
		)
		(pin "A11"
		)
		(pin "B5"
		)
		(pin "B9"
		)
		(pin "A5"
		)
		(pin "A9"
		)
		(pin "B4"
		)
		(pin "A4"
		)
		(pin "B6"
		)
		(pin "B2"
		)
		(pin "B11"
		)
		(pin "A10"
		)
		(instances
			(project "jetson-agx-thor-baseboard"
				(path ""
					(reference "J9")
					(unit 1)
				)
			)
		)
	)
	(symbol
		(lib_id "antmicroResistors0402:R_1k_0402")
		(at 179.07 201.93 0)
		(unit 1)
		(exclude_from_sim no)
		(in_bom no)
		(on_board yes)
		(dnp yes)
		(property "Reference" "R138"
			(at 184.785 201.295 0)
			(effects
				(font
					(size 1.27 1.27)
				)
				(justify left bottom)
			)
		)
		(property "Value" "R_1k_0402"
			(at 199.39 214.63 0)
			(effects
				(font
					(size 1.27 1.27)
					(thickness 0.15)
				)
				(justify left bottom)
				(hide yes)
			)
		)
		(property "Footprint" "antmicro-footprints:R_0402_1005Metric"
			(at 199.39 217.17 0)
			(effects
				(font
					(size 1.27 1.27)
					(thickness 0.15)
				)
				(justify left bottom)
				(hide yes)
			)
		)
		(property "Datasheet" "https://www.bourns.com/docs/product-datasheets/cr.pdf"
			(at 199.39 219.71 0)
			(effects
				(font
					(size 1.27 1.27)
					(thickness 0.15)
				)
				(justify left bottom)
				(hide yes)
			)
		)
		(property "Description" "SMD Chip Resistor, 1 kohm, ± 1%, 63 mW, 0402 [1005 Metric], Thick Film, General Purpose"
			(at 179.07 201.93 0)
			(effects
				(font
					(size 1.27 1.27)
				)
				(hide yes)
			)
		)
		(property "Manufacturer" "Bourns"
			(at 199.39 224.79 0)
			(effects
				(font
					(size 1.27 1.27)
					(thickness 0.15)
				)
				(justify left bottom)
				(hide yes)
			)
		)
		(property "MPN" "CR0402-FX-1001GLF"
			(at 199.39 222.25 0)
			(effects
				(font
					(size 1.27 1.27)
					(thickness 0.15)
				)
				(justify left bottom)
				(hide yes)
			)
		)
		(property "Val" "1k"
			(at 176.53 201.295 0)
			(effects
				(font
					(size 1.27 1.27)
					(thickness 0.15)
				)
				(justify left bottom)
			)
		)
		(property "License" "Apache-2.0"
			(at 199.39 227.33 0)
			(effects
				(font
					(size 1.27 1.27)
					(thickness 0.15)
				)
				(justify left bottom)
				(hide yes)
			)
		)
		(property "Author" "Antmicro"
			(at 199.39 229.87 0)
			(effects
				(font
					(size 1.27 1.27)
					(thickness 0.15)
				)
				(justify left bottom)
				(hide yes)
			)
		)
		(property "Tolerance" "1%"
			(at 199.39 212.09 0)
			(effects
				(font
					(size 1.27 1.27)
				)
				(justify left bottom)
				(hide yes)
			)
		)
		(pin "1"
		)
		(pin "2"
		)
		(instances
			(project "jetson-agx-thor-baseboard"
				(path ""
					(reference "R138")
					(unit 1)
				)
			)
		)
	)
	(symbol
		(lib_id "antmicroPMICPowerDistributionSwitchesLoadDrivers:AP22615A_TSOT26")
		(at 208.28 63.5 0)
		(unit 1)
		(exclude_from_sim no)
		(in_bom yes)
		(on_board yes)
		(dnp no)
		(property "Reference" "U35"
			(at 215.9 57.15 0)
			(effects
				(font
					(size 1.27 1.27)
				)
			)
		)
		(property "Value" "AP22615A_TSOT26"
			(at 238.76 68.58 0)
			(effects
				(font
					(size 1.27 1.27)
					(thickness 0.15)
				)
				(justify left bottom)
				(hide yes)
			)
		)
		(property "Footprint" "antmicro-footprints:TSOT23-6"
			(at 238.76 71.12 0)
			(effects
				(font
					(size 1.27 1.27)
					(thickness 0.15)
				)
				(justify left bottom)
				(hide yes)
			)
		)
		(property "Datasheet" "https://www.mouser.com/datasheet/2/115/DIOD_S_A0008958405_1-2543193.pdf"
			(at 238.76 73.66 0)
			(effects
				(font
					(size 1.27 1.27)
					(thickness 0.15)
				)
				(justify left bottom)
				(hide yes)
			)
		)
		(property "Description" "Power Load Distribution Switch, High Side, Active High, 1 Output, 5.5 V, 3.6 A, 0.04 ohm, TSOT-26-6"
			(at 208.28 63.5 0)
			(effects
				(font
					(size 1.27 1.27)
				)
				(hide yes)
			)
		)
		(property "MPN" "AP22615AWU-7"
			(at 215.9 59.69 0)
			(effects
				(font
					(size 1.27 1.27)
					(thickness 0.15)
				)
			)
		)
		(property "Manufacturer" "Diodes Incorporated"
			(at 238.76 78.74 0)
			(effects
				(font
					(size 1.27 1.27)
					(thickness 0.15)
				)
				(justify left bottom)
				(hide yes)
			)
		)
		(property "Author" "Antmicro"
			(at 238.76 81.28 0)
			(effects
				(font
					(size 1.27 1.27)
					(thickness 0.15)
				)
				(justify left bottom)
				(hide yes)
			)
		)
		(property "License" "Apache-2.0"
			(at 238.76 83.82 0)
			(effects
				(font
					(size 1.27 1.27)
					(thickness 0.15)
				)
				(justify left bottom)
				(hide yes)
			)
		)
		(pin "1"
		)
		(pin "2"
		)
		(pin "3"
		)
		(pin "4"
		)
		(pin "5"
		)
		(pin "6"
		)
		(instances
			(project "jetson-agx-thor-baseboard"
				(path ""
					(reference "U35")
					(unit 1)
				)
			)
		)
	)
	(symbol
		(lib_id "antmicropower:GND")
		(at 187.96 101.6 0)
		(mirror y)
		(unit 1)
		(exclude_from_sim no)
		(in_bom yes)
		(on_board yes)
		(dnp no)
		(property "Reference" "#PWR0252"
			(at 187.96 107.95 0)
			(effects
				(font
					(size 1.27 1.27)
				)
				(justify left bottom)
				(hide yes)
			)
		)
		(property "Value" "GND"
			(at 187.96 105.41 0)
			(effects
				(font
					(size 1.27 1.27)
					(thickness 0.15)
				)
			)
		)
		(property "Footprint" ""
			(at 179.07 109.22 0)
			(effects
				(font
					(size 1.27 1.27)
					(thickness 0.15)
				)
				(justify left bottom)
				(hide yes)
			)
		)
		(property "Datasheet" ""
			(at 179.07 114.3 0)
			(effects
				(font
					(size 1.27 1.27)
					(thickness 0.15)
				)
				(justify left bottom)
				(hide yes)
			)
		)
		(property "Description" ""
			(at 187.96 101.6 0)
			(effects
				(font
					(size 1.27 1.27)
				)
				(hide yes)
			)
		)
		(property "Author" "Antmicro"
			(at 179.07 109.22 0)
			(effects
				(font
					(size 1.27 1.27)
					(thickness 0.15)
				)
				(justify left bottom)
				(hide yes)
			)
		)
		(property "License" "Apache-2.0"
			(at 179.07 111.76 0)
			(effects
				(font
					(size 1.27 1.27)
					(thickness 0.15)
				)
				(justify left bottom)
				(hide yes)
			)
		)
		(pin "1"
		)
		(instances
			(project "jetson-agx-thor-baseboard"
				(path ""
					(reference "#PWR0252")
					(unit 1)
				)
			)
		)
	)
	(symbol
		(lib_id "antmicroResistors0402:R_1k_0402")
		(at 179.07 209.55 0)
		(unit 1)
		(exclude_from_sim no)
		(in_bom yes)
		(on_board yes)
		(dnp no)
		(property "Reference" "R141"
			(at 184.785 208.915 0)
			(effects
				(font
					(size 1.27 1.27)
				)
				(justify left bottom)
			)
		)
		(property "Value" "R_1k_0402"
			(at 199.39 222.25 0)
			(effects
				(font
					(size 1.27 1.27)
					(thickness 0.15)
				)
				(justify left bottom)
				(hide yes)
			)
		)
		(property "Footprint" "antmicro-footprints:R_0402_1005Metric"
			(at 199.39 224.79 0)
			(effects
				(font
					(size 1.27 1.27)
					(thickness 0.15)
				)
				(justify left bottom)
				(hide yes)
			)
		)
		(property "Datasheet" "https://www.bourns.com/docs/product-datasheets/cr.pdf"
			(at 199.39 227.33 0)
			(effects
				(font
					(size 1.27 1.27)
					(thickness 0.15)
				)
				(justify left bottom)
				(hide yes)
			)
		)
		(property "Description" "SMD Chip Resistor, 1 kohm, ± 1%, 63 mW, 0402 [1005 Metric], Thick Film, General Purpose"
			(at 179.07 209.55 0)
			(effects
				(font
					(size 1.27 1.27)
				)
				(hide yes)
			)
		)
		(property "Manufacturer" "Bourns"
			(at 199.39 232.41 0)
			(effects
				(font
					(size 1.27 1.27)
					(thickness 0.15)
				)
				(justify left bottom)
				(hide yes)
			)
		)
		(property "MPN" "CR0402-FX-1001GLF"
			(at 199.39 229.87 0)
			(effects
				(font
					(size 1.27 1.27)
					(thickness 0.15)
				)
				(justify left bottom)
				(hide yes)
			)
		)
		(property "Val" "1k"
			(at 176.53 208.915 0)
			(effects
				(font
					(size 1.27 1.27)
					(thickness 0.15)
				)
				(justify left bottom)
			)
		)
		(property "License" "Apache-2.0"
			(at 199.39 234.95 0)
			(effects
				(font
					(size 1.27 1.27)
					(thickness 0.15)
				)
				(justify left bottom)
				(hide yes)
			)
		)
		(property "Author" "Antmicro"
			(at 199.39 237.49 0)
			(effects
				(font
					(size 1.27 1.27)
					(thickness 0.15)
				)
				(justify left bottom)
				(hide yes)
			)
		)
		(property "Tolerance" "1%"
			(at 199.39 219.71 0)
			(effects
				(font
					(size 1.27 1.27)
				)
				(justify left bottom)
				(hide yes)
			)
		)
		(pin "1"
		)
		(pin "2"
		)
		(instances
			(project "jetson-agx-thor-baseboard"
				(path ""
					(reference "R141")
					(unit 1)
				)
			)
		)
	)
	(symbol
		(lib_id "antmicroResistors0402:R_0R_0402")
		(at 165.1 228.6 180)
		(unit 1)
		(exclude_from_sim no)
		(in_bom yes)
		(on_board yes)
		(dnp no)
		(property "Reference" "R118"
			(at 165.1 227.33 0)
			(effects
				(font
					(size 1.27 1.27)
				)
				(justify left top)
			)
		)
		(property "Value" "R_0R_0402"
			(at 144.78 215.9 0)
			(effects
				(font
					(size 1.27 1.27)
					(thickness 0.15)
				)
				(justify left bottom)
				(hide yes)
			)
		)
		(property "Footprint" "antmicro-footprints:R_0402_1005Metric"
			(at 144.78 213.36 0)
			(effects
				(font
					(size 1.27 1.27)
					(thickness 0.15)
				)
				(justify left bottom)
				(hide yes)
			)
		)
		(property "Datasheet" "https://industrial.panasonic.com/cdbs/www-data/pdf/RDA0000/AOA0000C301.pdf"
			(at 144.78 210.82 0)
			(effects
				(font
					(size 1.27 1.27)
					(thickness 0.15)
				)
				(justify left bottom)
				(hide yes)
			)
		)
		(property "Description" "SMD Chip Resistor, Jumper, 0 ohm, 100 mW, 0402 [1005 Metric], Thick Film, General Purpose"
			(at 165.1 228.6 0)
			(effects
				(font
					(size 1.27 1.27)
				)
				(hide yes)
			)
		)
		(property "Manufacturer" "Panasonic"
			(at 144.78 205.74 0)
			(effects
				(font
					(size 1.27 1.27)
					(thickness 0.15)
				)
				(justify left bottom)
				(hide yes)
			)
		)
		(property "MPN" "ERJ2GE0R00X"
			(at 144.78 208.28 0)
			(effects
				(font
					(size 1.27 1.27)
					(thickness 0.15)
				)
				(justify left bottom)
				(hide yes)
			)
		)
		(property "Val" "0R"
			(at 163.83 231.394 0)
			(effects
				(font
					(size 1.27 1.27)
					(thickness 0.15)
				)
				(justify left top)
			)
		)
		(property "License" "Apache-2.0"
			(at 144.78 203.2 0)
			(effects
				(font
					(size 1.27 1.27)
					(thickness 0.15)
				)
				(justify left bottom)
				(hide yes)
			)
		)
		(property "Author" "Antmicro"
			(at 144.78 200.66 0)
			(effects
				(font
					(size 1.27 1.27)
					(thickness 0.15)
				)
				(justify left bottom)
				(hide yes)
			)
		)
		(property "Tolerance" "~"
			(at 144.78 218.44 0)
			(effects
				(font
					(size 1.27 1.27)
				)
				(justify left bottom)
				(hide yes)
			)
		)
		(property "Current" "1A"
			(at 144.78 198.12 0)
			(effects
				(font
					(size 1.27 1.27)
					(thickness 0.15)
				)
				(justify left bottom)
				(hide yes)
			)
		)
		(pin "1"
		)
		(pin "2"
		)
		(instances
			(project "jetson-agx-thor-baseboard"
				(path ""
					(reference "R118")
					(unit 1)
				)
			)
		)
	)
	(symbol
		(lib_id "antmicroResistors0402:R_2M_0402")
		(at 289.56 170.18 270)
		(unit 1)
		(exclude_from_sim no)
		(in_bom yes)
		(on_board yes)
		(dnp no)
		(property "Reference" "R155"
			(at 290.83 171.45 90)
			(effects
				(font
					(size 1.27 1.27)
					(thickness 0.15)
				)
				(justify left)
			)
		)
		(property "Value" "R_2M_0402"
			(at 276.86 190.5 0)
			(effects
				(font
					(size 1.27 1.27)
					(thickness 0.15)
				)
				(justify left bottom)
				(hide yes)
			)
		)
		(property "Footprint" "antmicro-footprints:R_0402_1005Metric"
			(at 274.32 190.5 0)
			(effects
				(font
					(size 1.27 1.27)
					(thickness 0.15)
				)
				(justify left bottom)
				(hide yes)
			)
		)
		(property "Datasheet" "https://www.mouser.com/datasheet/2/447/YAGEO_PYu_RC_Group_51_RoHS_L_12-3313492.pdf"
			(at 271.78 190.5 0)
			(effects
				(font
					(size 1.27 1.27)
					(thickness 0.15)
				)
				(justify left bottom)
				(hide yes)
			)
		)
		(property "Description" "SMD Chip Resistor, 2 Mohm, ± 1%, 62.5 mW, 0402 [1005 Metric], Thick Film, General Purpose"
			(at 289.56 170.18 0)
			(effects
				(font
					(size 1.27 1.27)
				)
				(hide yes)
			)
		)
		(property "MPN" "RC0402FR-072ML"
			(at 269.24 190.5 0)
			(effects
				(font
					(size 1.27 1.27)
					(thickness 0.15)
				)
				(justify left bottom)
				(hide yes)
			)
		)
		(property "Manufacturer" "YAGEO"
			(at 266.7 190.5 0)
			(effects
				(font
					(size 1.27 1.27)
					(thickness 0.15)
				)
				(justify left bottom)
				(hide yes)
			)
		)
		(property "License" "Apache-2.0"
			(at 264.16 190.5 0)
			(effects
				(font
					(size 1.27 1.27)
					(thickness 0.15)
				)
				(justify left bottom)
				(hide yes)
			)
		)
		(property "Author" "Antmicro"
			(at 261.62 190.5 0)
			(effects
				(font
					(size 1.27 1.27)
					(thickness 0.15)
				)
				(justify left bottom)
				(hide yes)
			)
		)
		(property "Val" "2M"
			(at 290.83 173.99 90)
			(effects
				(font
					(size 1.27 1.27)
					(thickness 0.15)
				)
				(justify left)
			)
		)
		(property "Tolerance" "1%"
			(at 279.4 190.5 0)
			(effects
				(font
					(size 1.27 1.27)
				)
				(justify left bottom)
				(hide yes)
			)
		)
		(pin "1"
		)
		(pin "2"
		)
		(instances
			(project "jetson-agx-thor-baseboard"
				(path ""
					(reference "R155")
					(unit 1)
				)
			)
		)
	)
	(symbol
		(lib_id "antmicropower:GND")
		(at 97.79 217.17 0)
		(mirror y)
		(unit 1)
		(exclude_from_sim no)
		(in_bom yes)
		(on_board yes)
		(dnp no)
		(property "Reference" "#PWR0481"
			(at 97.79 223.52 0)
			(effects
				(font
					(size 1.27 1.27)
				)
				(justify left bottom)
				(hide yes)
			)
		)
		(property "Value" "GND"
			(at 97.79 220.98 0)
			(effects
				(font
					(size 1.27 1.27)
					(thickness 0.15)
				)
			)
		)
		(property "Footprint" ""
			(at 88.9 224.79 0)
			(effects
				(font
					(size 1.27 1.27)
					(thickness 0.15)
				)
				(justify left bottom)
				(hide yes)
			)
		)
		(property "Datasheet" ""
			(at 88.9 229.87 0)
			(effects
				(font
					(size 1.27 1.27)
					(thickness 0.15)
				)
				(justify left bottom)
				(hide yes)
			)
		)
		(property "Description" ""
			(at 97.79 217.17 0)
			(effects
				(font
					(size 1.27 1.27)
				)
				(hide yes)
			)
		)
		(property "Author" "Antmicro"
			(at 88.9 224.79 0)
			(effects
				(font
					(size 1.27 1.27)
					(thickness 0.15)
				)
				(justify left bottom)
				(hide yes)
			)
		)
		(property "License" "Apache-2.0"
			(at 88.9 227.33 0)
			(effects
				(font
					(size 1.27 1.27)
					(thickness 0.15)
				)
				(justify left bottom)
				(hide yes)
			)
		)
		(pin "1"
		)
		(instances
			(project "jetson-agx-thor-baseboard"
				(path ""
					(reference "#PWR0481")
					(unit 1)
				)
			)
		)
	)
	(symbol
		(lib_id "antmicroResistors0402:R_0R_0402")
		(at 91.44 209.55 0)
		(mirror x)
		(unit 1)
		(exclude_from_sim no)
		(in_bom yes)
		(on_board yes)
		(dnp no)
		(property "Reference" "R227"
			(at 91.186 208.28 0)
			(effects
				(font
					(size 1.27 1.27)
				)
				(justify left top)
			)
		)
		(property "Value" "R_0R_0402"
			(at 111.76 196.85 0)
			(effects
				(font
					(size 1.27 1.27)
					(thickness 0.15)
				)
				(justify left bottom)
				(hide yes)
			)
		)
		(property "Footprint" "antmicro-footprints:R_0402_1005Metric"
			(at 111.76 194.31 0)
			(effects
				(font
					(size 1.27 1.27)
					(thickness 0.15)
				)
				(justify left bottom)
				(hide yes)
			)
		)
		(property "Datasheet" "https://industrial.panasonic.com/cdbs/www-data/pdf/RDA0000/AOA0000C301.pdf"
			(at 111.76 191.77 0)
			(effects
				(font
					(size 1.27 1.27)
					(thickness 0.15)
				)
				(justify left bottom)
				(hide yes)
			)
		)
		(property "Description" "SMD Chip Resistor, Jumper, 0 ohm, 100 mW, 0402 [1005 Metric], Thick Film, General Purpose"
			(at 91.44 209.55 0)
			(effects
				(font
					(size 1.27 1.27)
				)
				(hide yes)
			)
		)
		(property "Manufacturer" "Panasonic"
			(at 111.76 186.69 0)
			(effects
				(font
					(size 1.27 1.27)
					(thickness 0.15)
				)
				(justify left bottom)
				(hide yes)
			)
		)
		(property "MPN" "ERJ2GE0R00X"
			(at 111.76 189.23 0)
			(effects
				(font
					(size 1.27 1.27)
					(thickness 0.15)
				)
				(justify left bottom)
				(hide yes)
			)
		)
		(property "Val" "0R"
			(at 92.71 212.598 0)
			(effects
				(font
					(size 1.27 1.27)
					(thickness 0.15)
				)
				(justify left top)
			)
		)
		(property "License" "Apache-2.0"
			(at 111.76 184.15 0)
			(effects
				(font
					(size 1.27 1.27)
					(thickness 0.15)
				)
				(justify left bottom)
				(hide yes)
			)
		)
		(property "Author" "Antmicro"
			(at 111.76 181.61 0)
			(effects
				(font
					(size 1.27 1.27)
					(thickness 0.15)
				)
				(justify left bottom)
				(hide yes)
			)
		)
		(property "Tolerance" "~"
			(at 111.76 199.39 0)
			(effects
				(font
					(size 1.27 1.27)
				)
				(justify left bottom)
				(hide yes)
			)
		)
		(property "Current" "1A"
			(at 111.76 179.07 0)
			(effects
				(font
					(size 1.27 1.27)
					(thickness 0.15)
				)
				(justify left bottom)
				(hide yes)
			)
		)
		(pin "1"
		)
		(pin "2"
		)
		(instances
			(project "jetson-agx-thor-baseboard"
				(path ""
					(reference "R227")
					(unit 1)
				)
			)
		)
	)
	(symbol
		(lib_id "antmicroTVSDiodes:TPD4E05U06QDQARQ1")
		(at 288.29 97.79 270)
		(mirror x)
		(unit 1)
		(exclude_from_sim no)
		(in_bom yes)
		(on_board yes)
		(dnp no)
		(property "Reference" "U38"
			(at 283.845 85.09 90)
			(effects
				(font
					(size 1.27 1.27)
				)
			)
		)
		(property "Value" "TPD4E05U06QDQARQ1"
			(at 278.13 73.66 0)
			(effects
				(font
					(size 1.27 1.27)
					(thickness 0.15)
				)
				(justify left bottom)
				(hide yes)
			)
		)
		(property "Footprint" "antmicro-footprints:USON-10_2.5x1mm_P0.5mm"
			(at 283.21 73.66 0)
			(effects
				(font
					(size 1.27 1.27)
					(thickness 0.15)
				)
				(justify left bottom)
				(hide yes)
			)
		)
		(property "Datasheet" "https://www.ti.com/lit/ds/symlink/tpd4e05u06-q1.pdf?HQS=dis-mous-null-mousermode-dsf-pf-null-wwe&ts=1663591265741&ref_url=https%253A%252F%252Fwww.mouser.com%252F"
			(at 280.67 73.66 0)
			(effects
				(font
					(size 1.27 1.27)
					(thickness 0.15)
				)
				(justify left bottom)
				(hide yes)
			)
		)
		(property "Description" "TVS diode array, 12 kV, USON-10, 5.5 V, 0.5 pF"
			(at 288.29 97.79 0)
			(effects
				(font
					(size 1.27 1.27)
				)
				(hide yes)
			)
		)
		(property "Manufacturer" "Texas Instruments"
			(at 275.59 73.66 0)
			(effects
				(font
					(size 1.27 1.27)
					(thickness 0.15)
				)
				(justify left bottom)
				(hide yes)
			)
		)
		(property "MPN" "TPD4E05U06QDQARQ1"
			(at 281.94 87.63 90)
			(effects
				(font
					(size 1.27 1.27)
					(thickness 0.15)
				)
			)
		)
		(property "Author" "Antmicro"
			(at 273.05 73.66 0)
			(effects
				(font
					(size 1.27 1.27)
					(thickness 0.15)
				)
				(justify left bottom)
				(hide yes)
			)
		)
		(property "License" "Apache-2.0"
			(at 270.51 73.66 0)
			(effects
				(font
					(size 1.27 1.27)
					(thickness 0.15)
				)
				(justify left bottom)
				(hide yes)
			)
		)
		(pin "1"
		)
		(pin "10"
		)
		(pin "2"
		)
		(pin "3"
		)
		(pin "4"
		)
		(pin "5"
		)
		(pin "6"
		)
		(pin "7"
		)
		(pin "8"
		)
		(pin "9"
		)
		(instances
			(project "jetson-agx-thor-baseboard"
				(path ""
					(reference "U38")
					(unit 1)
				)
			)
		)
	)
	(symbol
		(lib_id "antmicroResistors0402:R_2k2_0402")
		(at 232.41 72.39 90)
		(unit 1)
		(exclude_from_sim no)
		(in_bom yes)
		(on_board yes)
		(dnp no)
		(property "Reference" "R146"
			(at 233.68 68.58 90)
			(effects
				(font
					(size 1.27 1.27)
				)
				(justify right)
			)
		)
		(property "Value" "R_2k2_0402"
			(at 245.11 52.07 0)
			(effects
				(font
					(size 1.27 1.27)
					(thickness 0.15)
				)
				(justify left bottom)
				(hide yes)
			)
		)
		(property "Footprint" "antmicro-footprints:R_0402_1005Metric"
			(at 247.65 52.07 0)
			(effects
				(font
					(size 1.27 1.27)
					(thickness 0.15)
				)
				(justify left bottom)
				(hide yes)
			)
		)
		(property "Datasheet" "https://www.bourns.com/docs/product-datasheets/cr.pdf"
			(at 250.19 52.07 0)
			(effects
				(font
					(size 1.27 1.27)
					(thickness 0.15)
				)
				(justify left bottom)
				(hide yes)
			)
		)
		(property "Description" "SMD Chip Resistor, 2.2 kohm, ± 1%, 62.5 mW, 0402 [1005 Metric], Thick Film, General Purpose"
			(at 232.41 72.39 0)
			(effects
				(font
					(size 1.27 1.27)
				)
				(hide yes)
			)
		)
		(property "Manufacturer" "Bourns"
			(at 255.27 52.07 0)
			(effects
				(font
					(size 1.27 1.27)
					(thickness 0.15)
				)
				(justify left bottom)
				(hide yes)
			)
		)
		(property "MPN" "CR0402-FX-2201GLF"
			(at 252.73 52.07 0)
			(effects
				(font
					(size 1.27 1.27)
					(thickness 0.15)
				)
				(justify left bottom)
				(hide yes)
			)
		)
		(property "Val" "2k2"
			(at 233.68 71.12 90)
			(effects
				(font
					(size 1.27 1.27)
					(thickness 0.15)
				)
				(justify right)
			)
		)
		(property "License" "Apache-2.0"
			(at 257.81 52.07 0)
			(effects
				(font
					(size 1.27 1.27)
					(thickness 0.15)
				)
				(justify left bottom)
				(hide yes)
			)
		)
		(property "Author" "Antmicro"
			(at 260.35 52.07 0)
			(effects
				(font
					(size 1.27 1.27)
					(thickness 0.15)
				)
				(justify left bottom)
				(hide yes)
			)
		)
		(property "Tolerance" "1%"
			(at 242.57 52.07 0)
			(effects
				(font
					(size 1.27 1.27)
				)
				(justify left bottom)
				(hide yes)
			)
		)
		(pin "1"
		)
		(pin "2"
		)
		(instances
			(project "jetson-agx-thor-baseboard"
				(path ""
					(reference "R146")
					(unit 1)
				)
			)
		)
	)
	(symbol
		(lib_id "antmicroCapacitors0402:C_10u_0402")
		(at 187.96 115.57 90)
		(mirror x)
		(unit 1)
		(exclude_from_sim no)
		(in_bom yes)
		(on_board yes)
		(dnp no)
		(fields_autoplaced yes)
		(property "Reference" "C139"
			(at 190.5 116.8463 90)
			(effects
				(font
					(size 1.27 1.27)
					(thickness 0.15)
				)
				(justify right)
			)
		)
		(property "Value" "C_10u_0402"
			(at 198.12 135.89 0)
			(effects
				(font
					(size 1.27 1.27)
					(thickness 0.15)
				)
				(justify left bottom)
				(hide yes)
			)
		)
		(property "Footprint" "antmicro-footprints:C_0402_1005Metric"
			(at 200.66 135.89 0)
			(effects
				(font
					(size 1.27 1.27)
					(thickness 0.15)
				)
				(justify left bottom)
				(hide yes)
			)
		)
		(property "Datasheet" "https://www.yageo.com/en/Chart/Download/pdf/CC0402MRX5R5BB106"
			(at 203.2 135.89 0)
			(effects
				(font
					(size 1.27 1.27)
					(thickness 0.15)
				)
				(justify left bottom)
				(hide yes)
			)
		)
		(property "Description" "SMD Multilayer Ceramic Capacitor, 10 µF, 6.3 V, 0402 [1005 Metric], ± 20%, X5R, CC Series"
			(at 187.96 115.57 0)
			(effects
				(font
					(size 1.27 1.27)
				)
				(hide yes)
			)
		)
		(property "MPN" "CC0402MRX5R5BB106"
			(at 205.74 135.89 0)
			(effects
				(font
					(size 1.27 1.27)
					(thickness 0.15)
				)
				(justify left bottom)
				(hide yes)
			)
		)
		(property "Manufacturer" "YAGEO"
			(at 208.28 135.89 0)
			(effects
				(font
					(size 1.27 1.27)
					(thickness 0.15)
				)
				(justify left bottom)
				(hide yes)
			)
		)
		(property "License" "Apache-2.0"
			(at 210.82 135.89 0)
			(effects
				(font
					(size 1.27 1.27)
					(thickness 0.15)
				)
				(justify left bottom)
				(hide yes)
			)
		)
		(property "Author" "Antmicro"
			(at 213.36 135.89 0)
			(effects
				(font
					(size 1.27 1.27)
					(thickness 0.15)
				)
				(justify left bottom)
				(hide yes)
			)
		)
		(property "Val" "10u"
			(at 190.5 119.3863 90)
			(effects
				(font
					(size 1.27 1.27)
					(thickness 0.15)
				)
				(justify right)
			)
		)
		(property "Voltage" ""
			(at 215.9 135.89 0)
			(effects
				(font
					(size 1.27 1.27)
				)
				(justify left bottom)
				(hide yes)
			)
		)
		(property "Dielectric" ""
			(at 218.44 135.89 0)
			(effects
				(font
					(size 1.27 1.27)
				)
				(justify left bottom)
				(hide yes)
			)
		)
		(pin "1"
		)
		(pin "2"
		)
		(instances
			(project "jetson-agx-thor-baseboard"
				(path ""
					(reference "C139")
					(unit 1)
				)
			)
		)
	)
	(symbol
		(lib_id "antmicroResistors0402:R_10k_0402")
		(at 143.51 227.33 90)
		(unit 1)
		(exclude_from_sim no)
		(in_bom yes)
		(on_board yes)
		(dnp no)
		(fields_autoplaced yes)
		(property "Reference" "R274"
			(at 146.05 223.52 90)
			(effects
				(font
					(size 1.27 1.27)
					(thickness 0.15)
				)
				(justify right)
			)
		)
		(property "Value" "R_10k_0402"
			(at 156.21 207.01 0)
			(effects
				(font
					(size 1.27 1.27)
					(thickness 0.15)
				)
				(justify left bottom)
				(hide yes)
			)
		)
		(property "Footprint" "antmicro-footprints:R_0402_1005Metric"
			(at 158.75 207.01 0)
			(effects
				(font
					(size 1.27 1.27)
					(thickness 0.15)
				)
				(justify left bottom)
				(hide yes)
			)
		)
		(property "Datasheet" "https://www.bourns.com/docs/product-datasheets/cr.pdf"
			(at 161.29 207.01 0)
			(effects
				(font
					(size 1.27 1.27)
					(thickness 0.15)
				)
				(justify left bottom)
				(hide yes)
			)
		)
		(property "Description" "SMD Chip Resistor, 10 kohm, ± 1%, 62.5 mW, 0402 [1005 Metric], Thick Film, General Purpose"
			(at 173.99 207.01 0)
			(effects
				(font
					(size 1.27 1.27)
				)
				(justify left bottom)
				(hide yes)
			)
		)
		(property "MPN" "CR0402-FX-1002GLF"
			(at 163.83 207.01 0)
			(effects
				(font
					(size 1.27 1.27)
					(thickness 0.15)
				)
				(justify left bottom)
				(hide yes)
			)
		)
		(property "Manufacturer" "Bourns"
			(at 166.37 207.01 0)
			(effects
				(font
					(size 1.27 1.27)
					(thickness 0.15)
				)
				(justify left bottom)
				(hide yes)
			)
		)
		(property "License" "Apache-2.0"
			(at 168.91 207.01 0)
			(effects
				(font
					(size 1.27 1.27)
					(thickness 0.15)
				)
				(justify left bottom)
				(hide yes)
			)
		)
		(property "Author" "Antmicro"
			(at 171.45 207.01 0)
			(effects
				(font
					(size 1.27 1.27)
					(thickness 0.15)
				)
				(justify left bottom)
				(hide yes)
			)
		)
		(property "Val" "10k"
			(at 146.05 226.06 90)
			(effects
				(font
					(size 1.27 1.27)
					(thickness 0.15)
				)
				(justify right)
			)
		)
		(property "Tolerance" "1%"
			(at 153.67 207.01 0)
			(effects
				(font
					(size 1.27 1.27)
				)
				(justify left bottom)
				(hide yes)
			)
		)
		(pin "1"
		)
		(pin "2"
		)
		(instances
			(project "jetson-agx-thor-baseboard"
				(path ""
					(reference "R274")
					(unit 1)
				)
			)
		)
	)
	(symbol
		(lib_id "antmicroCapacitors0402:C_4u7_25V_0402")
		(at 187.96 95.25 270)
		(unit 1)
		(exclude_from_sim no)
		(in_bom yes)
		(on_board yes)
		(dnp no)
		(fields_autoplaced yes)
		(property "Reference" "C138"
			(at 190.5 96.5263 90)
			(effects
				(font
					(size 1.27 1.27)
				)
				(justify left)
			)
		)
		(property "Value" "C_4u7_25V_0402"
			(at 177.8 115.57 0)
			(effects
				(font
					(size 1.27 1.27)
					(thickness 0.15)
				)
				(justify left bottom)
				(hide yes)
			)
		)
		(property "Footprint" "antmicro-footprints:C_0402_1005Metric"
			(at 175.26 115.57 0)
			(effects
				(font
					(size 1.27 1.27)
					(thickness 0.15)
				)
				(justify left bottom)
				(hide yes)
			)
		)
		(property "Datasheet" "https://www.murata.com/products/productdetail?partno=GRM155C61E475ME15%23"
			(at 172.72 115.57 0)
			(effects
				(font
					(size 1.27 1.27)
					(thickness 0.15)
				)
				(justify left bottom)
				(hide yes)
			)
		)
		(property "Description" "SMD Multilayer Ceramic Capacitor"
			(at 187.96 95.25 0)
			(effects
				(font
					(size 1.27 1.27)
				)
				(hide yes)
			)
		)
		(property "Manufacturer" "Murata"
			(at 167.64 115.57 0)
			(effects
				(font
					(size 1.27 1.27)
					(thickness 0.15)
				)
				(justify left bottom)
				(hide yes)
			)
		)
		(property "MPN" "GRM155C61E475ME15J"
			(at 170.18 115.57 0)
			(effects
				(font
					(size 1.27 1.27)
					(thickness 0.15)
				)
				(justify left bottom)
				(hide yes)
			)
		)
		(property "Val" "4u7"
			(at 190.5 99.0663 90)
			(effects
				(font
					(size 1.27 1.27)
					(thickness 0.15)
				)
				(justify left)
			)
		)
		(property "License" "Apache-2.0"
			(at 165.1 115.57 0)
			(effects
				(font
					(size 1.27 1.27)
					(thickness 0.15)
				)
				(justify left bottom)
				(hide yes)
			)
		)
		(property "Author" "Antmicro"
			(at 162.56 115.57 0)
			(effects
				(font
					(size 1.27 1.27)
					(thickness 0.15)
				)
				(justify left bottom)
				(hide yes)
			)
		)
		(property "Voltage" "25V"
			(at 160.02 115.57 0)
			(effects
				(font
					(size 1.27 1.27)
				)
				(justify left bottom)
				(hide yes)
			)
		)
		(property "Dielectric" "X5S"
			(at 157.48 115.57 0)
			(effects
				(font
					(size 1.27 1.27)
				)
				(justify left bottom)
				(hide yes)
			)
		)
		(pin "1"
		)
		(pin "2"
		)
		(instances
			(project "jetson-agx-thor-baseboard"
				(path ""
					(reference "C138")
					(unit 1)
				)
			)
		)
	)
	(symbol
		(lib_id "antmicroResistors0402:R_1k_0402")
		(at 179.07 181.61 0)
		(unit 1)
		(exclude_from_sim no)
		(in_bom no)
		(on_board yes)
		(dnp yes)
		(property "Reference" "R130"
			(at 184.785 180.975 0)
			(effects
				(font
					(size 1.27 1.27)
				)
				(justify left bottom)
				(hide yes)
			)
		)
		(property "Value" "R_1k_0402"
			(at 199.39 194.31 0)
			(effects
				(font
					(size 1.27 1.27)
					(thickness 0.15)
				)
				(justify left bottom)
				(hide yes)
			)
		)
		(property "Footprint" "antmicro-footprints:R_0402_1005Metric"
			(at 199.39 196.85 0)
			(effects
				(font
					(size 1.27 1.27)
					(thickness 0.15)
				)
				(justify left bottom)
				(hide yes)
			)
		)
		(property "Datasheet" "https://www.bourns.com/docs/product-datasheets/cr.pdf"
			(at 199.39 199.39 0)
			(effects
				(font
					(size 1.27 1.27)
					(thickness 0.15)
				)
				(justify left bottom)
				(hide yes)
			)
		)
		(property "Description" "SMD Chip Resistor, 1 kohm, ± 1%, 63 mW, 0402 [1005 Metric], Thick Film, General Purpose"
			(at 179.07 181.61 0)
			(effects
				(font
					(size 1.27 1.27)
				)
				(hide yes)
			)
		)
		(property "Manufacturer" "Bourns"
			(at 199.39 204.47 0)
			(effects
				(font
					(size 1.27 1.27)
					(thickness 0.15)
				)
				(justify left bottom)
				(hide yes)
			)
		)
		(property "MPN" "CR0402-FX-1001GLF"
			(at 199.39 201.93 0)
			(effects
				(font
					(size 1.27 1.27)
					(thickness 0.15)
				)
				(justify left bottom)
				(hide yes)
			)
		)
		(property "Val" "1k"
			(at 176.53 180.975 0)
			(effects
				(font
					(size 1.27 1.27)
					(thickness 0.15)
				)
				(justify left bottom)
				(hide yes)
			)
		)
		(property "License" "Apache-2.0"
			(at 199.39 207.01 0)
			(effects
				(font
					(size 1.27 1.27)
					(thickness 0.15)
				)
				(justify left bottom)
				(hide yes)
			)
		)
		(property "Author" "Antmicro"
			(at 199.39 209.55 0)
			(effects
				(font
					(size 1.27 1.27)
					(thickness 0.15)
				)
				(justify left bottom)
				(hide yes)
			)
		)
		(property "Tolerance" "1%"
			(at 199.39 191.77 0)
			(effects
				(font
					(size 1.27 1.27)
				)
				(justify left bottom)
				(hide yes)
			)
		)
		(pin "1"
		)
		(pin "2"
		)
		(instances
			(project "jetson-agx-thor-baseboard"
				(path ""
					(reference "R130")
					(unit 1)
				)
			)
		)
	)
	(symbol
		(lib_id "antmicroResistors0402:R_4k7_0402")
		(at 297.18 69.85 90)
		(unit 1)
		(exclude_from_sim no)
		(in_bom yes)
		(on_board yes)
		(dnp no)
		(property "Reference" "R157"
			(at 298.45 66.04 90)
			(effects
				(font
					(size 1.27 1.27)
				)
				(justify right)
			)
		)
		(property "Value" "R_4k7_0402"
			(at 309.88 49.53 0)
			(effects
				(font
					(size 1.27 1.27)
					(thickness 0.15)
				)
				(justify left bottom)
				(hide yes)
			)
		)
		(property "Footprint" "antmicro-footprints:R_0402_1005Metric"
			(at 312.42 49.53 0)
			(effects
				(font
					(size 1.27 1.27)
					(thickness 0.15)
				)
				(justify left bottom)
				(hide yes)
			)
		)
		(property "Datasheet" "https://www.bourns.com/docs/product-datasheets/cr.pdf"
			(at 314.96 49.53 0)
			(effects
				(font
					(size 1.27 1.27)
					(thickness 0.15)
				)
				(justify left bottom)
				(hide yes)
			)
		)
		(property "Description" "SMD Chip Resistor, 4.7 kohm, ± 1%, 62.5 mW, 0402 [1005 Metric], Thick Film, General Purpose"
			(at 297.18 69.85 0)
			(effects
				(font
					(size 1.27 1.27)
				)
				(hide yes)
			)
		)
		(property "Manufacturer" "Bourns"
			(at 320.04 49.53 0)
			(effects
				(font
					(size 1.27 1.27)
					(thickness 0.15)
				)
				(justify left bottom)
				(hide yes)
			)
		)
		(property "MPN" "CR0402-FX-4701GLF"
			(at 317.5 49.53 0)
			(effects
				(font
					(size 1.27 1.27)
					(thickness 0.15)
				)
				(justify left bottom)
				(hide yes)
			)
		)
		(property "Val" "4k7"
			(at 298.45 68.58 90)
			(effects
				(font
					(size 1.27 1.27)
					(thickness 0.15)
				)
				(justify right)
			)
		)
		(property "License" "Apache-2.0"
			(at 322.58 49.53 0)
			(effects
				(font
					(size 1.27 1.27)
					(thickness 0.15)
				)
				(justify left bottom)
				(hide yes)
			)
		)
		(property "Author" "Antmicro"
			(at 325.12 49.53 0)
			(effects
				(font
					(size 1.27 1.27)
					(thickness 0.15)
				)
				(justify left bottom)
				(hide yes)
			)
		)
		(property "Tolerance" "1%"
			(at 307.34 49.53 0)
			(effects
				(font
					(size 1.27 1.27)
				)
				(justify left bottom)
				(hide yes)
			)
		)
		(pin "1"
		)
		(pin "2"
		)
		(instances
			(project "jetson-agx-thor-baseboard"
				(path ""
					(reference "R157")
					(unit 1)
				)
			)
		)
	)
	(symbol
		(lib_id "antmicropower:GND")
		(at 287.02 71.12 0)
		(mirror y)
		(unit 1)
		(exclude_from_sim no)
		(in_bom yes)
		(on_board yes)
		(dnp no)
		(property "Reference" "#PWR0281"
			(at 287.02 77.47 0)
			(effects
				(font
					(size 1.27 1.27)
				)
				(justify left bottom)
				(hide yes)
			)
		)
		(property "Value" "GND"
			(at 287.02 74.93 0)
			(effects
				(font
					(size 1.27 1.27)
					(thickness 0.15)
				)
			)
		)
		(property "Footprint" ""
			(at 278.13 78.74 0)
			(effects
				(font
					(size 1.27 1.27)
					(thickness 0.15)
				)
				(justify left bottom)
				(hide yes)
			)
		)
		(property "Datasheet" ""
			(at 278.13 83.82 0)
			(effects
				(font
					(size 1.27 1.27)
					(thickness 0.15)
				)
				(justify left bottom)
				(hide yes)
			)
		)
		(property "Description" ""
			(at 287.02 71.12 0)
			(effects
				(font
					(size 1.27 1.27)
				)
				(hide yes)
			)
		)
		(property "Author" "Antmicro"
			(at 278.13 78.74 0)
			(effects
				(font
					(size 1.27 1.27)
					(thickness 0.15)
				)
				(justify left bottom)
				(hide yes)
			)
		)
		(property "License" "Apache-2.0"
			(at 278.13 81.28 0)
			(effects
				(font
					(size 1.27 1.27)
					(thickness 0.15)
				)
				(justify left bottom)
				(hide yes)
			)
		)
		(pin "1"
		)
		(instances
			(project "jetson-agx-thor-baseboard"
				(path ""
					(reference "#PWR0281")
					(unit 1)
				)
			)
		)
	)
	(symbol
		(lib_id "antmicroCapacitors0402:C_100n_0402")
		(at 99.06 153.67 0)
		(mirror x)
		(unit 1)
		(exclude_from_sim no)
		(in_bom yes)
		(on_board yes)
		(dnp no)
		(property "Reference" "C129"
			(at 105.41 152.4 0)
			(effects
				(font
					(size 1.27 1.27)
				)
			)
		)
		(property "Value" "C_100n_0402"
			(at 119.38 143.51 0)
			(effects
				(font
					(size 1.27 1.27)
					(thickness 0.15)
				)
				(justify left bottom)
				(hide yes)
			)
		)
		(property "Footprint" "antmicro-footprints:C_0402_1005Metric"
			(at 119.38 140.97 0)
			(effects
				(font
					(size 1.27 1.27)
					(thickness 0.15)
				)
				(justify left bottom)
				(hide yes)
			)
		)
		(property "Datasheet" "https://www.murata.com/products/productdetail?partno=GRM155R61H104KE14%23"
			(at 119.38 138.43 0)
			(effects
				(font
					(size 1.27 1.27)
					(thickness 0.15)
				)
				(justify left bottom)
				(hide yes)
			)
		)
		(property "Description" "SMD Multilayer Ceramic Capacitor, 0.1 µF, 50 V, 0402 [1005 Metric], ± 10%, X5R, GRM Series"
			(at 99.06 153.67 0)
			(effects
				(font
					(size 1.27 1.27)
				)
				(hide yes)
			)
		)
		(property "Manufacturer" "Murata"
			(at 119.38 133.35 0)
			(effects
				(font
					(size 1.27 1.27)
					(thickness 0.15)
				)
				(justify left bottom)
				(hide yes)
			)
		)
		(property "MPN" "GRM155R61H104KE14D"
			(at 119.38 135.89 0)
			(effects
				(font
					(size 1.27 1.27)
					(thickness 0.15)
				)
				(justify left bottom)
				(hide yes)
			)
		)
		(property "Val" "100n"
			(at 97.79 154.94 0)
			(effects
				(font
					(size 1.27 1.27)
					(thickness 0.15)
				)
			)
		)
		(property "License" "Apache-2.0"
			(at 119.38 130.81 0)
			(effects
				(font
					(size 1.27 1.27)
					(thickness 0.15)
				)
				(justify left bottom)
				(hide yes)
			)
		)
		(property "Author" "Antmicro"
			(at 119.38 128.27 0)
			(effects
				(font
					(size 1.27 1.27)
					(thickness 0.15)
				)
				(justify left bottom)
				(hide yes)
			)
		)
		(property "Voltage" "50V"
			(at 119.38 125.73 0)
			(effects
				(font
					(size 1.27 1.27)
				)
				(justify left bottom)
				(hide yes)
			)
		)
		(property "Dielectric" "X5R"
			(at 119.38 123.19 0)
			(effects
				(font
					(size 1.27 1.27)
				)
				(justify left bottom)
				(hide yes)
			)
		)
		(pin "1"
		)
		(pin "2"
		)
		(instances
			(project "jetson-agx-thor-baseboard"
				(path ""
					(reference "C129")
					(unit 1)
				)
			)
		)
	)
	(symbol
		(lib_id "antmicroTransistorsFETsMOSFETsSingle:DMG1012T-7")
		(at 110.49 237.49 0)
		(unit 1)
		(exclude_from_sim no)
		(in_bom yes)
		(on_board yes)
		(dnp no)
		(fields_autoplaced yes)
		(property "Reference" "Q34"
			(at 120.65 233.68 0)
			(effects
				(font
					(size 1.27 1.27)
					(thickness 0.15)
				)
				(justify left)
			)
		)
		(property "Value" "DMG1012T-7"
			(at 120.65 241.3 0)
			(effects
				(font
					(size 1.27 1.27)
					(thickness 0.15)
				)
				(justify left bottom)
				(hide yes)
			)
		)
		(property "Footprint" "antmicro-footprints:SOT-523"
			(at 120.65 243.84 0)
			(effects
				(font
					(size 1.27 1.27)
					(thickness 0.15)
				)
				(justify left bottom)
				(hide yes)
			)
		)
		(property "Datasheet" "https://www.diodes.com/assets/Datasheets/ds31783.pdf"
			(at 120.65 246.38 0)
			(effects
				(font
					(size 1.27 1.27)
					(thickness 0.15)
				)
				(justify left bottom)
				(hide yes)
			)
		)
		(property "Description" "Power MOSFET, N Channel, 20 V, 630 mA, 0.3 ohm, SOT-523, Surface Mount"
			(at 120.65 254 0)
			(effects
				(font
					(size 1.27 1.27)
				)
				(justify left bottom)
				(hide yes)
			)
		)
		(property "MPN" "DMG1012T-7"
			(at 120.65 236.22 0)
			(effects
				(font
					(size 1.27 1.27)
					(thickness 0.15)
				)
				(justify left)
			)
		)
		(property "Manufacturer" "Diodes Incorporated"
			(at 120.65 238.76 0)
			(effects
				(font
					(size 1.27 1.27)
					(thickness 0.15)
				)
				(justify left bottom)
				(hide yes)
			)
		)
		(property "Author" "Antmicro"
			(at 120.65 248.92 0)
			(effects
				(font
					(size 1.27 1.27)
					(thickness 0.15)
				)
				(justify left bottom)
				(hide yes)
			)
		)
		(property "License" "Apache-2.0"
			(at 120.65 251.46 0)
			(effects
				(font
					(size 1.27 1.27)
					(thickness 0.15)
				)
				(justify left bottom)
				(hide yes)
			)
		)
		(pin "1"
		)
		(pin "3"
		)
		(pin "2"
		)
		(instances
			(project ""
				(path ""
					(reference "Q34")
					(unit 1)
				)
			)
		)
	)
	(symbol
		(lib_id "antmicroCapacitors0402:C_100n_0402")
		(at 105.41 104.14 90)
		(mirror x)
		(unit 1)
		(exclude_from_sim no)
		(in_bom yes)
		(on_board yes)
		(dnp no)
		(property "Reference" "C131"
			(at 107.315 105.41 90)
			(effects
				(font
					(size 1.27 1.27)
				)
				(justify right)
			)
		)
		(property "Value" "C_100n_0402"
			(at 115.57 124.46 0)
			(effects
				(font
					(size 1.27 1.27)
					(thickness 0.15)
				)
				(justify left bottom)
				(hide yes)
			)
		)
		(property "Footprint" "antmicro-footprints:C_0402_1005Metric"
			(at 118.11 124.46 0)
			(effects
				(font
					(size 1.27 1.27)
					(thickness 0.15)
				)
				(justify left bottom)
				(hide yes)
			)
		)
		(property "Datasheet" "https://www.murata.com/products/productdetail?partno=GRM155R61H104KE14%23"
			(at 120.65 124.46 0)
			(effects
				(font
					(size 1.27 1.27)
					(thickness 0.15)
				)
				(justify left bottom)
				(hide yes)
			)
		)
		(property "Description" "SMD Multilayer Ceramic Capacitor, 0.1 µF, 50 V, 0402 [1005 Metric], ± 10%, X5R, GRM Series"
			(at 105.41 104.14 0)
			(effects
				(font
					(size 1.27 1.27)
				)
				(hide yes)
			)
		)
		(property "Manufacturer" "Murata"
			(at 125.73 124.46 0)
			(effects
				(font
					(size 1.27 1.27)
					(thickness 0.15)
				)
				(justify left bottom)
				(hide yes)
			)
		)
		(property "MPN" "GRM155R61H104KE14D"
			(at 123.19 124.46 0)
			(effects
				(font
					(size 1.27 1.27)
					(thickness 0.15)
				)
				(justify left bottom)
				(hide yes)
			)
		)
		(property "Val" "100n"
			(at 107.315 107.95 90)
			(effects
				(font
					(size 1.27 1.27)
					(thickness 0.15)
				)
				(justify right)
			)
		)
		(property "License" "Apache-2.0"
			(at 128.27 124.46 0)
			(effects
				(font
					(size 1.27 1.27)
					(thickness 0.15)
				)
				(justify left bottom)
				(hide yes)
			)
		)
		(property "Author" "Antmicro"
			(at 130.81 124.46 0)
			(effects
				(font
					(size 1.27 1.27)
					(thickness 0.15)
				)
				(justify left bottom)
				(hide yes)
			)
		)
		(property "Voltage" "50V"
			(at 133.35 124.46 0)
			(effects
				(font
					(size 1.27 1.27)
				)
				(justify left bottom)
				(hide yes)
			)
		)
		(property "Dielectric" "X5R"
			(at 135.89 124.46 0)
			(effects
				(font
					(size 1.27 1.27)
				)
				(justify left bottom)
				(hide yes)
			)
		)
		(pin "1"
		)
		(pin "2"
		)
		(instances
			(project "jetson-agx-thor-baseboard"
				(path ""
					(reference "C131")
					(unit 1)
				)
			)
		)
	)
	(symbol
		(lib_id "antmicroTVSDiodes:TPD4E05U06QDQARQ1")
		(at 228.6 172.72 270)
		(unit 1)
		(exclude_from_sim no)
		(in_bom yes)
		(on_board yes)
		(dnp no)
		(fields_autoplaced yes)
		(property "Reference" "U36"
			(at 224.155 184.15 90)
			(effects
				(font
					(size 1.27 1.27)
				)
			)
		)
		(property "Value" "TPD4E05U06QDQARQ1"
			(at 218.44 196.85 0)
			(effects
				(font
					(size 1.27 1.27)
					(thickness 0.15)
				)
				(justify left bottom)
				(hide yes)
			)
		)
		(property "Footprint" "antmicro-footprints:USON-10_2.5x1mm_P0.5mm"
			(at 223.52 196.85 0)
			(effects
				(font
					(size 1.27 1.27)
					(thickness 0.15)
				)
				(justify left bottom)
				(hide yes)
			)
		)
		(property "Datasheet" "https://www.ti.com/lit/ds/symlink/tpd4e05u06-q1.pdf?HQS=dis-mous-null-mousermode-dsf-pf-null-wwe&ts=1663591265741&ref_url=https%253A%252F%252Fwww.mouser.com%252F"
			(at 220.98 196.85 0)
			(effects
				(font
					(size 1.27 1.27)
					(thickness 0.15)
				)
				(justify left bottom)
				(hide yes)
			)
		)
		(property "Description" "TVS diode array, 12 kV, USON-10, 5.5 V, 0.5 pF"
			(at 228.6 172.72 0)
			(effects
				(font
					(size 1.27 1.27)
				)
				(hide yes)
			)
		)
		(property "Manufacturer" "Texas Instruments"
			(at 215.9 196.85 0)
			(effects
				(font
					(size 1.27 1.27)
					(thickness 0.15)
				)
				(justify left bottom)
				(hide yes)
			)
		)
		(property "MPN" "TPD4E05U06QDQARQ1"
			(at 224.155 186.69 90)
			(effects
				(font
					(size 1.27 1.27)
					(thickness 0.15)
				)
			)
		)
		(property "Author" "Antmicro"
			(at 213.36 196.85 0)
			(effects
				(font
					(size 1.27 1.27)
					(thickness 0.15)
				)
				(justify left bottom)
				(hide yes)
			)
		)
		(property "License" "Apache-2.0"
			(at 210.82 196.85 0)
			(effects
				(font
					(size 1.27 1.27)
					(thickness 0.15)
				)
				(justify left bottom)
				(hide yes)
			)
		)
		(pin "1"
		)
		(pin "10"
		)
		(pin "2"
		)
		(pin "3"
		)
		(pin "4"
		)
		(pin "5"
		)
		(pin "6"
		)
		(pin "7"
		)
		(pin "8"
		)
		(pin "9"
		)
		(instances
			(project "jetson-agx-thor-baseboard"
				(path ""
					(reference "U36")
					(unit 1)
				)
			)
		)
	)
	(symbol
		(lib_id "antmicropower:GND")
		(at 93.98 110.49 0)
		(mirror y)
		(unit 1)
		(exclude_from_sim no)
		(in_bom yes)
		(on_board yes)
		(dnp no)
		(property "Reference" "#PWR0238"
			(at 93.98 116.84 0)
			(effects
				(font
					(size 1.27 1.27)
				)
				(justify left bottom)
				(hide yes)
			)
		)
		(property "Value" "GND"
			(at 93.98 114.3 0)
			(effects
				(font
					(size 1.27 1.27)
					(thickness 0.15)
				)
			)
		)
		(property "Footprint" ""
			(at 85.09 118.11 0)
			(effects
				(font
					(size 1.27 1.27)
					(thickness 0.15)
				)
				(justify left bottom)
				(hide yes)
			)
		)
		(property "Datasheet" ""
			(at 85.09 123.19 0)
			(effects
				(font
					(size 1.27 1.27)
					(thickness 0.15)
				)
				(justify left bottom)
				(hide yes)
			)
		)
		(property "Description" ""
			(at 93.98 110.49 0)
			(effects
				(font
					(size 1.27 1.27)
				)
				(hide yes)
			)
		)
		(property "Author" "Antmicro"
			(at 85.09 118.11 0)
			(effects
				(font
					(size 1.27 1.27)
					(thickness 0.15)
				)
				(justify left bottom)
				(hide yes)
			)
		)
		(property "License" "Apache-2.0"
			(at 85.09 120.65 0)
			(effects
				(font
					(size 1.27 1.27)
					(thickness 0.15)
				)
				(justify left bottom)
				(hide yes)
			)
		)
		(pin "1"
		)
		(instances
			(project "jetson-agx-thor-baseboard"
				(path ""
					(reference "#PWR0238")
					(unit 1)
				)
			)
		)
	)
	(symbol
		(lib_id "antmicroCapacitors0402:C_100n_0402")
		(at 172.72 143.51 0)
		(mirror x)
		(unit 1)
		(exclude_from_sim no)
		(in_bom yes)
		(on_board yes)
		(dnp no)
		(property "Reference" "C141"
			(at 181.61 142.24 0)
			(effects
				(font
					(size 1.27 1.27)
				)
				(justify right)
			)
		)
		(property "Value" "C_100n_0402"
			(at 193.04 133.35 0)
			(effects
				(font
					(size 1.27 1.27)
					(thickness 0.15)
				)
				(justify left bottom)
				(hide yes)
			)
		)
		(property "Footprint" "antmicro-footprints:C_0402_1005Metric"
			(at 193.04 130.81 0)
			(effects
				(font
					(size 1.27 1.27)
					(thickness 0.15)
				)
				(justify left bottom)
				(hide yes)
			)
		)
		(property "Datasheet" "https://www.murata.com/products/productdetail?partno=GRM155R61H104KE14%23"
			(at 193.04 128.27 0)
			(effects
				(font
					(size 1.27 1.27)
					(thickness 0.15)
				)
				(justify left bottom)
				(hide yes)
			)
		)
		(property "Description" "SMD Multilayer Ceramic Capacitor, 0.1 µF, 50 V, 0402 [1005 Metric], ± 10%, X5R, GRM Series"
			(at 172.72 143.51 0)
			(effects
				(font
					(size 1.27 1.27)
				)
				(hide yes)
			)
		)
		(property "Manufacturer" "Murata"
			(at 193.04 123.19 0)
			(effects
				(font
					(size 1.27 1.27)
					(thickness 0.15)
				)
				(justify left bottom)
				(hide yes)
			)
		)
		(property "MPN" "GRM155R61H104KE14D"
			(at 193.04 125.73 0)
			(effects
				(font
					(size 1.27 1.27)
					(thickness 0.15)
				)
				(justify left bottom)
				(hide yes)
			)
		)
		(property "Val" "100n"
			(at 174.244 144.78 0)
			(effects
				(font
					(size 1.27 1.27)
					(thickness 0.15)
				)
				(justify right)
			)
		)
		(property "License" "Apache-2.0"
			(at 193.04 120.65 0)
			(effects
				(font
					(size 1.27 1.27)
					(thickness 0.15)
				)
				(justify left bottom)
				(hide yes)
			)
		)
		(property "Author" "Antmicro"
			(at 193.04 118.11 0)
			(effects
				(font
					(size 1.27 1.27)
					(thickness 0.15)
				)
				(justify left bottom)
				(hide yes)
			)
		)
		(property "Voltage" "50V"
			(at 193.04 115.57 0)
			(effects
				(font
					(size 1.27 1.27)
				)
				(justify left bottom)
				(hide yes)
			)
		)
		(property "Dielectric" "X5R"
			(at 193.04 113.03 0)
			(effects
				(font
					(size 1.27 1.27)
				)
				(justify left bottom)
				(hide yes)
			)
		)
		(pin "1"
		)
		(pin "2"
		)
		(instances
			(project "jetson-agx-thor-baseboard"
				(path ""
					(reference "C141")
					(unit 1)
				)
			)
		)
	)
	(symbol
		(lib_id "antmicroResistors0402:R_0R_0402")
		(at 189.23 55.88 90)
		(unit 1)
		(exclude_from_sim no)
		(in_bom no)
		(on_board yes)
		(dnp yes)
		(property "Reference" "R142"
			(at 190.5 52.07 90)
			(effects
				(font
					(size 1.27 1.27)
				)
				(justify right)
			)
		)
		(property "Value" "R_0R_0402"
			(at 201.93 35.56 0)
			(effects
				(font
					(size 1.27 1.27)
					(thickness 0.15)
				)
				(justify left bottom)
				(hide yes)
			)
		)
		(property "Footprint" "antmicro-footprints:R_0402_1005Metric"
			(at 204.47 35.56 0)
			(effects
				(font
					(size 1.27 1.27)
					(thickness 0.15)
				)
				(justify left bottom)
				(hide yes)
			)
		)
		(property "Datasheet" "https://industrial.panasonic.com/cdbs/www-data/pdf/RDA0000/AOA0000C301.pdf"
			(at 207.01 35.56 0)
			(effects
				(font
					(size 1.27 1.27)
					(thickness 0.15)
				)
				(justify left bottom)
				(hide yes)
			)
		)
		(property "Description" "SMD Chip Resistor, Jumper, 0 ohm, 100 mW, 0402 [1005 Metric], Thick Film, General Purpose"
			(at 189.23 55.88 0)
			(effects
				(font
					(size 1.27 1.27)
				)
				(hide yes)
			)
		)
		(property "Manufacturer" "Panasonic"
			(at 212.09 35.56 0)
			(effects
				(font
					(size 1.27 1.27)
					(thickness 0.15)
				)
				(justify left bottom)
				(hide yes)
			)
		)
		(property "MPN" "ERJ2GE0R00X"
			(at 209.55 35.56 0)
			(effects
				(font
					(size 1.27 1.27)
					(thickness 0.15)
				)
				(justify left bottom)
				(hide yes)
			)
		)
		(property "Val" "0R"
			(at 190.5 54.61 90)
			(effects
				(font
					(size 1.27 1.27)
					(thickness 0.15)
				)
				(justify right)
			)
		)
		(property "License" "Apache-2.0"
			(at 214.63 35.56 0)
			(effects
				(font
					(size 1.27 1.27)
					(thickness 0.15)
				)
				(justify left bottom)
				(hide yes)
			)
		)
		(property "Author" "Antmicro"
			(at 217.17 35.56 0)
			(effects
				(font
					(size 1.27 1.27)
					(thickness 0.15)
				)
				(justify left bottom)
				(hide yes)
			)
		)
		(property "Tolerance" "~"
			(at 199.39 35.56 0)
			(effects
				(font
					(size 1.27 1.27)
				)
				(justify left bottom)
				(hide yes)
			)
		)
		(property "Current" "1A"
			(at 219.71 35.56 0)
			(effects
				(font
					(size 1.27 1.27)
					(thickness 0.15)
				)
				(justify left bottom)
				(hide yes)
			)
		)
		(pin "1"
		)
		(pin "2"
		)
		(instances
			(project "jetson-agx-thor-baseboard"
				(path ""
					(reference "R142")
					(unit 1)
				)
			)
		)
	)
	(symbol
		(lib_id "antmicroResistors0402:R_2M_0402")
		(at 287.02 170.18 270)
		(unit 1)
		(exclude_from_sim no)
		(in_bom yes)
		(on_board yes)
		(dnp no)
		(property "Reference" "R154"
			(at 285.75 171.45 90)
			(effects
				(font
					(size 1.27 1.27)
					(thickness 0.15)
				)
				(justify right)
			)
		)
		(property "Value" "R_2M_0402"
			(at 274.32 190.5 0)
			(effects
				(font
					(size 1.27 1.27)
					(thickness 0.15)
				)
				(justify left bottom)
				(hide yes)
			)
		)
		(property "Footprint" "antmicro-footprints:R_0402_1005Metric"
			(at 271.78 190.5 0)
			(effects
				(font
					(size 1.27 1.27)
					(thickness 0.15)
				)
				(justify left bottom)
				(hide yes)
			)
		)
		(property "Datasheet" "https://www.mouser.com/datasheet/2/447/YAGEO_PYu_RC_Group_51_RoHS_L_12-3313492.pdf"
			(at 269.24 190.5 0)
			(effects
				(font
					(size 1.27 1.27)
					(thickness 0.15)
				)
				(justify left bottom)
				(hide yes)
			)
		)
		(property "Description" "SMD Chip Resistor, 2 Mohm, ± 1%, 62.5 mW, 0402 [1005 Metric], Thick Film, General Purpose"
			(at 287.02 170.18 0)
			(effects
				(font
					(size 1.27 1.27)
				)
				(hide yes)
			)
		)
		(property "MPN" "RC0402FR-072ML"
			(at 266.7 190.5 0)
			(effects
				(font
					(size 1.27 1.27)
					(thickness 0.15)
				)
				(justify left bottom)
				(hide yes)
			)
		)
		(property "Manufacturer" "YAGEO"
			(at 264.16 190.5 0)
			(effects
				(font
					(size 1.27 1.27)
					(thickness 0.15)
				)
				(justify left bottom)
				(hide yes)
			)
		)
		(property "License" "Apache-2.0"
			(at 261.62 190.5 0)
			(effects
				(font
					(size 1.27 1.27)
					(thickness 0.15)
				)
				(justify left bottom)
				(hide yes)
			)
		)
		(property "Author" "Antmicro"
			(at 259.08 190.5 0)
			(effects
				(font
					(size 1.27 1.27)
					(thickness 0.15)
				)
				(justify left bottom)
				(hide yes)
			)
		)
		(property "Val" "2M"
			(at 285.75 173.99 90)
			(effects
				(font
					(size 1.27 1.27)
					(thickness 0.15)
				)
				(justify right)
			)
		)
		(property "Tolerance" "1%"
			(at 276.86 190.5 0)
			(effects
				(font
					(size 1.27 1.27)
				)
				(justify left bottom)
				(hide yes)
			)
		)
		(pin "1"
		)
		(pin "2"
		)
		(instances
			(project "jetson-agx-thor-baseboard"
				(path ""
					(reference "R154")
					(unit 1)
				)
			)
		)
	)
	(symbol
		(lib_id "antmicropower:+3V3")
		(at 193.04 175.26 0)
		(unit 1)
		(exclude_from_sim no)
		(in_bom yes)
		(on_board yes)
		(dnp no)
		(property "Reference" "#PWR0257"
			(at 193.04 179.07 0)
			(effects
				(font
					(size 1.27 1.27)
				)
				(justify left bottom)
				(hide yes)
			)
		)
		(property "Value" "+3V3"
			(at 189.865 171.45 0)
			(effects
				(font
					(size 1.27 1.27)
					(thickness 0.15)
				)
				(justify left)
			)
		)
		(property "Footprint" ""
			(at 208.28 182.88 0)
			(effects
				(font
					(size 1.27 1.27)
					(thickness 0.15)
				)
				(justify left bottom)
				(hide yes)
			)
		)
		(property "Datasheet" ""
			(at 208.28 185.42 0)
			(effects
				(font
					(size 1.27 1.27)
					(thickness 0.15)
				)
				(justify left bottom)
				(hide yes)
			)
		)
		(property "Description" ""
			(at 193.04 175.26 0)
			(effects
				(font
					(size 1.27 1.27)
				)
				(hide yes)
			)
		)
		(property "Author" "Antmicro"
			(at 208.28 177.8 0)
			(effects
				(font
					(size 1.27 1.27)
					(thickness 0.15)
				)
				(justify left bottom)
				(hide yes)
			)
		)
		(property "License" "Apache-2.0"
			(at 208.28 180.34 0)
			(effects
				(font
					(size 1.27 1.27)
					(thickness 0.15)
				)
				(justify left bottom)
				(hide yes)
			)
		)
		(pin "1"
		)
		(instances
			(project "jetson-agx-thor-baseboard"
				(path ""
					(reference "#PWR0257")
					(unit 1)
				)
			)
		)
	)
	(symbol
		(lib_id "antmicropower:GND")
		(at 105.41 110.49 0)
		(mirror y)
		(unit 1)
		(exclude_from_sim no)
		(in_bom yes)
		(on_board yes)
		(dnp no)
		(property "Reference" "#PWR0242"
			(at 105.41 116.84 0)
			(effects
				(font
					(size 1.27 1.27)
				)
				(justify left bottom)
				(hide yes)
			)
		)
		(property "Value" "GND"
			(at 105.41 114.3 0)
			(effects
				(font
					(size 1.27 1.27)
					(thickness 0.15)
				)
			)
		)
		(property "Footprint" ""
			(at 96.52 118.11 0)
			(effects
				(font
					(size 1.27 1.27)
					(thickness 0.15)
				)
				(justify left bottom)
				(hide yes)
			)
		)
		(property "Datasheet" ""
			(at 96.52 123.19 0)
			(effects
				(font
					(size 1.27 1.27)
					(thickness 0.15)
				)
				(justify left bottom)
				(hide yes)
			)
		)
		(property "Description" ""
			(at 105.41 110.49 0)
			(effects
				(font
					(size 1.27 1.27)
				)
				(hide yes)
			)
		)
		(property "Author" "Antmicro"
			(at 96.52 118.11 0)
			(effects
				(font
					(size 1.27 1.27)
					(thickness 0.15)
				)
				(justify left bottom)
				(hide yes)
			)
		)
		(property "License" "Apache-2.0"
			(at 96.52 120.65 0)
			(effects
				(font
					(size 1.27 1.27)
					(thickness 0.15)
				)
				(justify left bottom)
				(hide yes)
			)
		)
		(pin "1"
		)
		(instances
			(project "jetson-agx-thor-baseboard"
				(path ""
					(reference "#PWR0242")
					(unit 1)
				)
			)
		)
	)
	(symbol
		(lib_id "antmicroCapacitors0402:C_10u_0402")
		(at 72.39 109.22 90)
		(unit 1)
		(exclude_from_sim no)
		(in_bom yes)
		(on_board yes)
		(dnp no)
		(fields_autoplaced yes)
		(property "Reference" "C124"
			(at 75.565 105.4036 90)
			(effects
				(font
					(size 1.27 1.27)
					(thickness 0.15)
				)
				(justify right)
			)
		)
		(property "Value" "C_10u_0402"
			(at 82.55 88.9 0)
			(effects
				(font
					(size 1.27 1.27)
					(thickness 0.15)
				)
				(justify left bottom)
				(hide yes)
			)
		)
		(property "Footprint" "antmicro-footprints:C_0402_1005Metric"
			(at 85.09 88.9 0)
			(effects
				(font
					(size 1.27 1.27)
					(thickness 0.15)
				)
				(justify left bottom)
				(hide yes)
			)
		)
		(property "Datasheet" "https://www.yageo.com/en/Chart/Download/pdf/CC0402MRX5R5BB106"
			(at 87.63 88.9 0)
			(effects
				(font
					(size 1.27 1.27)
					(thickness 0.15)
				)
				(justify left bottom)
				(hide yes)
			)
		)
		(property "Description" "SMD Multilayer Ceramic Capacitor, 10 µF, 6.3 V, 0402 [1005 Metric], ± 20%, X5R, CC Series"
			(at 72.39 109.22 0)
			(effects
				(font
					(size 1.27 1.27)
				)
				(hide yes)
			)
		)
		(property "MPN" "CC0402MRX5R5BB106"
			(at 90.17 88.9 0)
			(effects
				(font
					(size 1.27 1.27)
					(thickness 0.15)
				)
				(justify left bottom)
				(hide yes)
			)
		)
		(property "Manufacturer" "YAGEO"
			(at 92.71 88.9 0)
			(effects
				(font
					(size 1.27 1.27)
					(thickness 0.15)
				)
				(justify left bottom)
				(hide yes)
			)
		)
		(property "License" "Apache-2.0"
			(at 95.25 88.9 0)
			(effects
				(font
					(size 1.27 1.27)
					(thickness 0.15)
				)
				(justify left bottom)
				(hide yes)
			)
		)
		(property "Author" "Antmicro"
			(at 97.79 88.9 0)
			(effects
				(font
					(size 1.27 1.27)
					(thickness 0.15)
				)
				(justify left bottom)
				(hide yes)
			)
		)
		(property "Val" "10u"
			(at 75.565 107.9436 90)
			(effects
				(font
					(size 1.27 1.27)
					(thickness 0.15)
				)
				(justify right)
			)
		)
		(property "Voltage" ""
			(at 100.33 88.9 0)
			(effects
				(font
					(size 1.27 1.27)
				)
				(justify left bottom)
				(hide yes)
			)
		)
		(property "Dielectric" ""
			(at 102.87 88.9 0)
			(effects
				(font
					(size 1.27 1.27)
				)
				(justify left bottom)
				(hide yes)
			)
		)
		(pin "1"
		)
		(pin "2"
		)
		(instances
			(project "jetson-agx-thor-baseboard"
				(path ""
					(reference "C124")
					(unit 1)
				)
			)
		)
	)
	(symbol
		(lib_id "antmicroResistors0402:R_1k_0402")
		(at 179.07 186.69 0)
		(unit 1)
		(exclude_from_sim no)
		(in_bom no)
		(on_board yes)
		(dnp yes)
		(property "Reference" "R132"
			(at 184.785 186.055 0)
			(effects
				(font
					(size 1.27 1.27)
				)
				(justify left bottom)
			)
		)
		(property "Value" "R_1k_0402"
			(at 199.39 199.39 0)
			(effects
				(font
					(size 1.27 1.27)
					(thickness 0.15)
				)
				(justify left bottom)
				(hide yes)
			)
		)
		(property "Footprint" "antmicro-footprints:R_0402_1005Metric"
			(at 199.39 201.93 0)
			(effects
				(font
					(size 1.27 1.27)
					(thickness 0.15)
				)
				(justify left bottom)
				(hide yes)
			)
		)
		(property "Datasheet" "https://www.bourns.com/docs/product-datasheets/cr.pdf"
			(at 199.39 204.47 0)
			(effects
				(font
					(size 1.27 1.27)
					(thickness 0.15)
				)
				(justify left bottom)
				(hide yes)
			)
		)
		(property "Description" "SMD Chip Resistor, 1 kohm, ± 1%, 63 mW, 0402 [1005 Metric], Thick Film, General Purpose"
			(at 179.07 186.69 0)
			(effects
				(font
					(size 1.27 1.27)
				)
				(hide yes)
			)
		)
		(property "Manufacturer" "Bourns"
			(at 199.39 209.55 0)
			(effects
				(font
					(size 1.27 1.27)
					(thickness 0.15)
				)
				(justify left bottom)
				(hide yes)
			)
		)
		(property "MPN" "CR0402-FX-1001GLF"
			(at 199.39 207.01 0)
			(effects
				(font
					(size 1.27 1.27)
					(thickness 0.15)
				)
				(justify left bottom)
				(hide yes)
			)
		)
		(property "Val" "1k"
			(at 176.53 186.055 0)
			(effects
				(font
					(size 1.27 1.27)
					(thickness 0.15)
				)
				(justify left bottom)
			)
		)
		(property "License" "Apache-2.0"
			(at 199.39 212.09 0)
			(effects
				(font
					(size 1.27 1.27)
					(thickness 0.15)
				)
				(justify left bottom)
				(hide yes)
			)
		)
		(property "Author" "Antmicro"
			(at 199.39 214.63 0)
			(effects
				(font
					(size 1.27 1.27)
					(thickness 0.15)
				)
				(justify left bottom)
				(hide yes)
			)
		)
		(property "Tolerance" "1%"
			(at 199.39 196.85 0)
			(effects
				(font
					(size 1.27 1.27)
				)
				(justify left bottom)
				(hide yes)
			)
		)
		(pin "1"
		)
		(pin "2"
		)
		(instances
			(project "jetson-agx-thor-baseboard"
				(path ""
					(reference "R132")
					(unit 1)
				)
			)
		)
	)
	(symbol
		(lib_id "antmicroInterfaceControllers:TPS65988DHRSHR")
		(at 233.68 110.49 0)
		(mirror y)
		(unit 3)
		(exclude_from_sim no)
		(in_bom yes)
		(on_board yes)
		(dnp no)
		(property "Reference" "U30"
			(at 217.805 101.6 0)
			(effects
				(font
					(size 1.27 1.27)
				)
			)
		)
		(property "Value" "TPS65988DHRSHR"
			(at 184.15 115.57 0)
			(effects
				(font
					(size 1.27 1.27)
					(thickness 0.15)
				)
				(justify left bottom)
				(hide yes)
			)
		)
		(property "Footprint" "antmicro-footprints:IC_TPS65987DDHRSHR"
			(at 184.15 118.11 0)
			(effects
				(font
					(size 1.27 1.27)
					(thickness 0.15)
				)
				(justify left bottom)
				(hide yes)
			)
		)
		(property "Datasheet" "https://www.ti.com/lit/ds/symlink/tps65988.pdf?ts=1662726631004&ref_url=https%253A%252F%252Fwww.ti.com%252Fproduct%252FTPS65988"
			(at 184.15 120.65 0)
			(effects
				(font
					(size 1.27 1.27)
					(thickness 0.15)
				)
				(justify left bottom)
				(hide yes)
			)
		)
		(property "Description" "USB, Type-C Controller PMIC 56-VQFN (7x7)"
			(at 233.68 110.49 0)
			(effects
				(font
					(size 1.27 1.27)
				)
				(hide yes)
			)
		)
		(property "MPN" "TPS65988DHRSHR "
			(at 217.805 104.14 0)
			(effects
				(font
					(size 1.27 1.27)
					(thickness 0.15)
				)
			)
		)
		(property "Manufacturer" "Texas Instruments"
			(at 184.15 125.73 0)
			(effects
				(font
					(size 1.27 1.27)
					(thickness 0.15)
				)
				(justify left bottom)
				(hide yes)
			)
		)
		(property "License" "Apache-2.0"
			(at 184.15 128.27 0)
			(effects
				(font
					(size 1.27 1.27)
					(thickness 0.15)
				)
				(justify left bottom)
				(hide yes)
			)
		)
		(property "Author" "Antmicro"
			(at 184.15 130.81 0)
			(effects
				(font
					(size 1.27 1.27)
					(thickness 0.15)
				)
				(justify left bottom)
				(hide yes)
			)
		)
		(pin "10"
		)
		(pin "16"
		)
		(pin "17"
		)
		(pin "18"
		)
		(pin "20"
		)
		(pin "21"
		)
		(pin "22"
		)
		(pin "23"
		)
		(pin "27"
		)
		(pin "28"
		)
		(pin "29"
		)
		(pin "30"
		)
		(pin "31"
		)
		(pin "32"
		)
		(pin "33"
		)
		(pin "34"
		)
		(pin "35"
		)
		(pin "36"
		)
		(pin "37"
		)
		(pin "38"
		)
		(pin "39"
		)
		(pin "40"
		)
		(pin "41"
		)
		(pin "42"
		)
		(pin "43"
		)
		(pin "44"
		)
		(pin "48"
		)
		(pin "49"
		)
		(pin "5"
		)
		(pin "51"
		)
		(pin "59"
		)
		(pin "6"
		)
		(pin "9"
		)
		(pin "11"
		)
		(pin "13"
		)
		(pin "15"
		)
		(pin "19"
		)
		(pin "24"
		)
		(pin "25"
		)
		(pin "26"
		)
		(pin "50"
		)
		(pin "53"
		)
		(pin "58"
		)
		(pin "8"
		)
		(pin "1"
		)
		(pin "3"
		)
		(pin "45"
		)
		(pin "46"
		)
		(pin "47"
		)
		(pin "52"
		)
		(pin "54"
		)
		(pin "55"
		)
		(pin "56"
		)
		(pin "57"
		)
		(pin "7"
		)
		(instances
			(project "jetson-agx-thor-baseboard"
				(path ""
					(reference "U30")
					(unit 3)
				)
			)
		)
	)
	(symbol
		(lib_id "antmicropower:GND")
		(at 261.62 71.12 0)
		(mirror y)
		(unit 1)
		(exclude_from_sim no)
		(in_bom yes)
		(on_board yes)
		(dnp no)
		(property "Reference" "#PWR0273"
			(at 261.62 77.47 0)
			(effects
				(font
					(size 1.27 1.27)
				)
				(justify left bottom)
				(hide yes)
			)
		)
		(property "Value" "GND"
			(at 261.62 74.93 0)
			(effects
				(font
					(size 1.27 1.27)
					(thickness 0.15)
				)
			)
		)
		(property "Footprint" ""
			(at 252.73 78.74 0)
			(effects
				(font
					(size 1.27 1.27)
					(thickness 0.15)
				)
				(justify left bottom)
				(hide yes)
			)
		)
		(property "Datasheet" ""
			(at 252.73 83.82 0)
			(effects
				(font
					(size 1.27 1.27)
					(thickness 0.15)
				)
				(justify left bottom)
				(hide yes)
			)
		)
		(property "Description" ""
			(at 261.62 71.12 0)
			(effects
				(font
					(size 1.27 1.27)
				)
				(hide yes)
			)
		)
		(property "Author" "Antmicro"
			(at 252.73 78.74 0)
			(effects
				(font
					(size 1.27 1.27)
					(thickness 0.15)
				)
				(justify left bottom)
				(hide yes)
			)
		)
		(property "License" "Apache-2.0"
			(at 252.73 81.28 0)
			(effects
				(font
					(size 1.27 1.27)
					(thickness 0.15)
				)
				(justify left bottom)
				(hide yes)
			)
		)
		(pin "1"
		)
		(instances
			(project "jetson-agx-thor-baseboard"
				(path ""
					(reference "#PWR0273")
					(unit 1)
				)
			)
		)
	)
	(symbol
		(lib_id "antmicroResistors0402:R_1k_0402")
		(at 179.07 184.15 0)
		(unit 1)
		(exclude_from_sim no)
		(in_bom no)
		(on_board yes)
		(dnp yes)
		(property "Reference" "R131"
			(at 184.785 183.515 0)
			(effects
				(font
					(size 1.27 1.27)
				)
				(justify left bottom)
			)
		)
		(property "Value" "R_1k_0402"
			(at 199.39 196.85 0)
			(effects
				(font
					(size 1.27 1.27)
					(thickness 0.15)
				)
				(justify left bottom)
				(hide yes)
			)
		)
		(property "Footprint" "antmicro-footprints:R_0402_1005Metric"
			(at 199.39 199.39 0)
			(effects
				(font
					(size 1.27 1.27)
					(thickness 0.15)
				)
				(justify left bottom)
				(hide yes)
			)
		)
		(property "Datasheet" "https://www.bourns.com/docs/product-datasheets/cr.pdf"
			(at 199.39 201.93 0)
			(effects
				(font
					(size 1.27 1.27)
					(thickness 0.15)
				)
				(justify left bottom)
				(hide yes)
			)
		)
		(property "Description" "SMD Chip Resistor, 1 kohm, ± 1%, 63 mW, 0402 [1005 Metric], Thick Film, General Purpose"
			(at 179.07 184.15 0)
			(effects
				(font
					(size 1.27 1.27)
				)
				(hide yes)
			)
		)
		(property "Manufacturer" "Bourns"
			(at 199.39 207.01 0)
			(effects
				(font
					(size 1.27 1.27)
					(thickness 0.15)
				)
				(justify left bottom)
				(hide yes)
			)
		)
		(property "MPN" "CR0402-FX-1001GLF"
			(at 199.39 204.47 0)
			(effects
				(font
					(size 1.27 1.27)
					(thickness 0.15)
				)
				(justify left bottom)
				(hide yes)
			)
		)
		(property "Val" "1k"
			(at 176.53 183.515 0)
			(effects
				(font
					(size 1.27 1.27)
					(thickness 0.15)
				)
				(justify left bottom)
			)
		)
		(property "License" "Apache-2.0"
			(at 199.39 209.55 0)
			(effects
				(font
					(size 1.27 1.27)
					(thickness 0.15)
				)
				(justify left bottom)
				(hide yes)
			)
		)
		(property "Author" "Antmicro"
			(at 199.39 212.09 0)
			(effects
				(font
					(size 1.27 1.27)
					(thickness 0.15)
				)
				(justify left bottom)
				(hide yes)
			)
		)
		(property "Tolerance" "1%"
			(at 199.39 194.31 0)
			(effects
				(font
					(size 1.27 1.27)
				)
				(justify left bottom)
				(hide yes)
			)
		)
		(pin "1"
		)
		(pin "2"
		)
		(instances
			(project "jetson-agx-thor-baseboard"
				(path ""
					(reference "R131")
					(unit 1)
				)
			)
		)
	)
	(symbol
		(lib_id "antmicropower:GND")
		(at 276.86 71.12 0)
		(mirror y)
		(unit 1)
		(exclude_from_sim no)
		(in_bom yes)
		(on_board yes)
		(dnp no)
		(property "Reference" "#PWR0277"
			(at 276.86 77.47 0)
			(effects
				(font
					(size 1.27 1.27)
				)
				(justify left bottom)
				(hide yes)
			)
		)
		(property "Value" "GND"
			(at 276.86 74.93 0)
			(effects
				(font
					(size 1.27 1.27)
					(thickness 0.15)
				)
			)
		)
		(property "Footprint" ""
			(at 267.97 78.74 0)
			(effects
				(font
					(size 1.27 1.27)
					(thickness 0.15)
				)
				(justify left bottom)
				(hide yes)
			)
		)
		(property "Datasheet" ""
			(at 267.97 83.82 0)
			(effects
				(font
					(size 1.27 1.27)
					(thickness 0.15)
				)
				(justify left bottom)
				(hide yes)
			)
		)
		(property "Description" ""
			(at 276.86 71.12 0)
			(effects
				(font
					(size 1.27 1.27)
				)
				(hide yes)
			)
		)
		(property "Author" "Antmicro"
			(at 267.97 78.74 0)
			(effects
				(font
					(size 1.27 1.27)
					(thickness 0.15)
				)
				(justify left bottom)
				(hide yes)
			)
		)
		(property "License" "Apache-2.0"
			(at 267.97 81.28 0)
			(effects
				(font
					(size 1.27 1.27)
					(thickness 0.15)
				)
				(justify left bottom)
				(hide yes)
			)
		)
		(pin "1"
		)
		(instances
			(project "jetson-agx-thor-baseboard"
				(path ""
					(reference "#PWR0277")
					(unit 1)
				)
			)
		)
	)
	(symbol
		(lib_id "antmicropower:GND")
		(at 187.96 121.92 0)
		(mirror y)
		(unit 1)
		(exclude_from_sim no)
		(in_bom yes)
		(on_board yes)
		(dnp no)
		(property "Reference" "#PWR0254"
			(at 187.96 128.27 0)
			(effects
				(font
					(size 1.27 1.27)
				)
				(justify left bottom)
				(hide yes)
			)
		)
		(property "Value" "GND"
			(at 187.96 125.73 0)
			(effects
				(font
					(size 1.27 1.27)
					(thickness 0.15)
				)
			)
		)
		(property "Footprint" ""
			(at 179.07 129.54 0)
			(effects
				(font
					(size 1.27 1.27)
					(thickness 0.15)
				)
				(justify left bottom)
				(hide yes)
			)
		)
		(property "Datasheet" ""
			(at 179.07 134.62 0)
			(effects
				(font
					(size 1.27 1.27)
					(thickness 0.15)
				)
				(justify left bottom)
				(hide yes)
			)
		)
		(property "Description" ""
			(at 187.96 121.92 0)
			(effects
				(font
					(size 1.27 1.27)
				)
				(hide yes)
			)
		)
		(property "Author" "Antmicro"
			(at 179.07 129.54 0)
			(effects
				(font
					(size 1.27 1.27)
					(thickness 0.15)
				)
				(justify left bottom)
				(hide yes)
			)
		)
		(property "License" "Apache-2.0"
			(at 179.07 132.08 0)
			(effects
				(font
					(size 1.27 1.27)
					(thickness 0.15)
				)
				(justify left bottom)
				(hide yes)
			)
		)
		(pin "1"
		)
		(instances
			(project "jetson-agx-thor-baseboard"
				(path ""
					(reference "#PWR0254")
					(unit 1)
				)
			)
		)
	)
	(symbol
		(lib_id "antmicroResistors0402:R_1k_0402")
		(at 179.07 204.47 0)
		(unit 1)
		(exclude_from_sim no)
		(in_bom no)
		(on_board yes)
		(dnp yes)
		(property "Reference" "R139"
			(at 184.785 203.835 0)
			(effects
				(font
					(size 1.27 1.27)
				)
				(justify left bottom)
			)
		)
		(property "Value" "R_1k_0402"
			(at 199.39 217.17 0)
			(effects
				(font
					(size 1.27 1.27)
					(thickness 0.15)
				)
				(justify left bottom)
				(hide yes)
			)
		)
		(property "Footprint" "antmicro-footprints:R_0402_1005Metric"
			(at 199.39 219.71 0)
			(effects
				(font
					(size 1.27 1.27)
					(thickness 0.15)
				)
				(justify left bottom)
				(hide yes)
			)
		)
		(property "Datasheet" "https://www.bourns.com/docs/product-datasheets/cr.pdf"
			(at 199.39 222.25 0)
			(effects
				(font
					(size 1.27 1.27)
					(thickness 0.15)
				)
				(justify left bottom)
				(hide yes)
			)
		)
		(property "Description" "SMD Chip Resistor, 1 kohm, ± 1%, 63 mW, 0402 [1005 Metric], Thick Film, General Purpose"
			(at 179.07 204.47 0)
			(effects
				(font
					(size 1.27 1.27)
				)
				(hide yes)
			)
		)
		(property "Manufacturer" "Bourns"
			(at 199.39 227.33 0)
			(effects
				(font
					(size 1.27 1.27)
					(thickness 0.15)
				)
				(justify left bottom)
				(hide yes)
			)
		)
		(property "MPN" "CR0402-FX-1001GLF"
			(at 199.39 224.79 0)
			(effects
				(font
					(size 1.27 1.27)
					(thickness 0.15)
				)
				(justify left bottom)
				(hide yes)
			)
		)
		(property "Val" "1k"
			(at 176.53 203.835 0)
			(effects
				(font
					(size 1.27 1.27)
					(thickness 0.15)
				)
				(justify left bottom)
			)
		)
		(property "License" "Apache-2.0"
			(at 199.39 229.87 0)
			(effects
				(font
					(size 1.27 1.27)
					(thickness 0.15)
				)
				(justify left bottom)
				(hide yes)
			)
		)
		(property "Author" "Antmicro"
			(at 199.39 232.41 0)
			(effects
				(font
					(size 1.27 1.27)
					(thickness 0.15)
				)
				(justify left bottom)
				(hide yes)
			)
		)
		(property "Tolerance" "1%"
			(at 199.39 214.63 0)
			(effects
				(font
					(size 1.27 1.27)
				)
				(justify left bottom)
				(hide yes)
			)
		)
		(pin "1"
		)
		(pin "2"
		)
		(instances
			(project "jetson-agx-thor-baseboard"
				(path ""
					(reference "R139")
					(unit 1)
				)
			)
		)
	)
	(symbol
		(lib_id "antmicroResistors0402:R_100k_0402")
		(at 90.17 180.34 90)
		(unit 1)
		(exclude_from_sim no)
		(in_bom yes)
		(on_board yes)
		(dnp no)
		(fields_autoplaced yes)
		(property "Reference" "R116"
			(at 92.71 176.53 90)
			(effects
				(font
					(size 1.27 1.27)
				)
				(justify right)
			)
		)
		(property "Value" "R_100k_0402"
			(at 102.87 160.02 0)
			(effects
				(font
					(size 1.27 1.27)
					(thickness 0.15)
				)
				(justify left bottom)
				(hide yes)
			)
		)
		(property "Footprint" "antmicro-footprints:R_0402_1005Metric"
			(at 105.41 160.02 0)
			(effects
				(font
					(size 1.27 1.27)
					(thickness 0.15)
				)
				(justify left bottom)
				(hide yes)
			)
		)
		(property "Datasheet" "https://www.bourns.com/docs/product-datasheets/cr.pdf"
			(at 107.95 160.02 0)
			(effects
				(font
					(size 1.27 1.27)
					(thickness 0.15)
				)
				(justify left bottom)
				(hide yes)
			)
		)
		(property "Description" "SMD Chip Resistor, 100 kohm, ± 1%, 62.5 mW, 0402 [1005 Metric], Thick Film, General Purpose"
			(at 90.17 180.34 0)
			(effects
				(font
					(size 1.27 1.27)
				)
				(hide yes)
			)
		)
		(property "Manufacturer" "Bourns"
			(at 113.03 160.02 0)
			(effects
				(font
					(size 1.27 1.27)
					(thickness 0.15)
				)
				(justify left bottom)
				(hide yes)
			)
		)
		(property "MPN" "CR0402-FX-1003GLF"
			(at 110.49 160.02 0)
			(effects
				(font
					(size 1.27 1.27)
					(thickness 0.15)
				)
				(justify left bottom)
				(hide yes)
			)
		)
		(property "Val" "100k"
			(at 92.71 179.07 90)
			(effects
				(font
					(size 1.27 1.27)
					(thickness 0.15)
				)
				(justify right)
			)
		)
		(property "License" "Apache-2.0"
			(at 115.57 160.02 0)
			(effects
				(font
					(size 1.27 1.27)
					(thickness 0.15)
				)
				(justify left bottom)
				(hide yes)
			)
		)
		(property "Author" "Antmicro"
			(at 118.11 160.02 0)
			(effects
				(font
					(size 1.27 1.27)
					(thickness 0.15)
				)
				(justify left bottom)
				(hide yes)
			)
		)
		(property "Tolerance" "1%"
			(at 100.33 160.02 0)
			(effects
				(font
					(size 1.27 1.27)
				)
				(justify left bottom)
				(hide yes)
			)
		)
		(pin "1"
		)
		(pin "2"
		)
		(instances
			(project "jetson-agx-thor-baseboard"
				(path ""
					(reference "R116")
					(unit 1)
				)
			)
		)
	)
	(symbol
		(lib_id "antmicroResistors0402:R_10k_0402")
		(at 204.47 74.93 90)
		(unit 1)
		(exclude_from_sim no)
		(in_bom yes)
		(on_board yes)
		(dnp no)
		(property "Reference" "R144"
			(at 205.74 71.12 90)
			(effects
				(font
					(size 1.27 1.27)
				)
				(justify right)
			)
		)
		(property "Value" "R_10k_0402"
			(at 217.17 54.61 0)
			(effects
				(font
					(size 1.27 1.27)
					(thickness 0.15)
				)
				(justify left bottom)
				(hide yes)
			)
		)
		(property "Footprint" "antmicro-footprints:R_0402_1005Metric"
			(at 219.71 54.61 0)
			(effects
				(font
					(size 1.27 1.27)
					(thickness 0.15)
				)
				(justify left bottom)
				(hide yes)
			)
		)
		(property "Datasheet" "https://www.bourns.com/docs/product-datasheets/cr.pdf"
			(at 222.25 54.61 0)
			(effects
				(font
					(size 1.27 1.27)
					(thickness 0.15)
				)
				(justify left bottom)
				(hide yes)
			)
		)
		(property "Description" "SMD Chip Resistor, 10 kohm, ± 1%, 62.5 mW, 0402 [1005 Metric], Thick Film, General Purpose"
			(at 204.47 74.93 0)
			(effects
				(font
					(size 1.27 1.27)
				)
				(hide yes)
			)
		)
		(property "Manufacturer" "Bourns"
			(at 227.33 54.61 0)
			(effects
				(font
					(size 1.27 1.27)
					(thickness 0.15)
				)
				(justify left bottom)
				(hide yes)
			)
		)
		(property "MPN" "CR0402-FX-1002GLF"
			(at 224.79 54.61 0)
			(effects
				(font
					(size 1.27 1.27)
					(thickness 0.15)
				)
				(justify left bottom)
				(hide yes)
			)
		)
		(property "Val" "10k"
			(at 205.74 73.66 90)
			(effects
				(font
					(size 1.27 1.27)
					(thickness 0.15)
				)
				(justify right)
			)
		)
		(property "License" "Apache-2.0"
			(at 229.87 54.61 0)
			(effects
				(font
					(size 1.27 1.27)
					(thickness 0.15)
				)
				(justify left bottom)
				(hide yes)
			)
		)
		(property "Author" "Antmicro"
			(at 232.41 54.61 0)
			(effects
				(font
					(size 1.27 1.27)
					(thickness 0.15)
				)
				(justify left bottom)
				(hide yes)
			)
		)
		(property "Tolerance" "1%"
			(at 214.63 54.61 0)
			(effects
				(font
					(size 1.27 1.27)
				)
				(justify left bottom)
				(hide yes)
			)
		)
		(pin "1"
		)
		(pin "2"
		)
		(instances
			(project "jetson-agx-thor-baseboard"
				(path ""
					(reference "R144")
					(unit 1)
				)
			)
		)
	)
	(symbol
		(lib_id "antmicropower:GND")
		(at 297.18 77.47 0)
		(mirror y)
		(unit 1)
		(exclude_from_sim no)
		(in_bom yes)
		(on_board yes)
		(dnp no)
		(property "Reference" "#PWR0285"
			(at 297.18 83.82 0)
			(effects
				(font
					(size 1.27 1.27)
				)
				(justify left bottom)
				(hide yes)
			)
		)
		(property "Value" "GND"
			(at 297.18 81.28 0)
			(effects
				(font
					(size 1.27 1.27)
					(thickness 0.15)
				)
			)
		)
		(property "Footprint" ""
			(at 288.29 85.09 0)
			(effects
				(font
					(size 1.27 1.27)
					(thickness 0.15)
				)
				(justify left bottom)
				(hide yes)
			)
		)
		(property "Datasheet" ""
			(at 288.29 90.17 0)
			(effects
				(font
					(size 1.27 1.27)
					(thickness 0.15)
				)
				(justify left bottom)
				(hide yes)
			)
		)
		(property "Description" ""
			(at 297.18 77.47 0)
			(effects
				(font
					(size 1.27 1.27)
				)
				(hide yes)
			)
		)
		(property "Author" "Antmicro"
			(at 288.29 85.09 0)
			(effects
				(font
					(size 1.27 1.27)
					(thickness 0.15)
				)
				(justify left bottom)
				(hide yes)
			)
		)
		(property "License" "Apache-2.0"
			(at 288.29 87.63 0)
			(effects
				(font
					(size 1.27 1.27)
					(thickness 0.15)
				)
				(justify left bottom)
				(hide yes)
			)
		)
		(pin "1"
		)
		(instances
			(project "jetson-agx-thor-baseboard"
				(path ""
					(reference "#PWR0285")
					(unit 1)
				)
			)
		)
	)
	(symbol
		(lib_id "antmicroResistors0402:R_1k_0402")
		(at 179.07 207.01 0)
		(unit 1)
		(exclude_from_sim no)
		(in_bom no)
		(on_board yes)
		(dnp yes)
		(property "Reference" "R140"
			(at 184.785 206.375 0)
			(effects
				(font
					(size 1.27 1.27)
				)
				(justify left bottom)
			)
		)
		(property "Value" "R_1k_0402"
			(at 199.39 219.71 0)
			(effects
				(font
					(size 1.27 1.27)
					(thickness 0.15)
				)
				(justify left bottom)
				(hide yes)
			)
		)
		(property "Footprint" "antmicro-footprints:R_0402_1005Metric"
			(at 199.39 222.25 0)
			(effects
				(font
					(size 1.27 1.27)
					(thickness 0.15)
				)
				(justify left bottom)
				(hide yes)
			)
		)
		(property "Datasheet" "https://www.bourns.com/docs/product-datasheets/cr.pdf"
			(at 199.39 224.79 0)
			(effects
				(font
					(size 1.27 1.27)
					(thickness 0.15)
				)
				(justify left bottom)
				(hide yes)
			)
		)
		(property "Description" "SMD Chip Resistor, 1 kohm, ± 1%, 63 mW, 0402 [1005 Metric], Thick Film, General Purpose"
			(at 179.07 207.01 0)
			(effects
				(font
					(size 1.27 1.27)
				)
				(hide yes)
			)
		)
		(property "Manufacturer" "Bourns"
			(at 199.39 229.87 0)
			(effects
				(font
					(size 1.27 1.27)
					(thickness 0.15)
				)
				(justify left bottom)
				(hide yes)
			)
		)
		(property "MPN" "CR0402-FX-1001GLF"
			(at 199.39 227.33 0)
			(effects
				(font
					(size 1.27 1.27)
					(thickness 0.15)
				)
				(justify left bottom)
				(hide yes)
			)
		)
		(property "Val" "1k"
			(at 176.53 206.375 0)
			(effects
				(font
					(size 1.27 1.27)
					(thickness 0.15)
				)
				(justify left bottom)
			)
		)
		(property "License" "Apache-2.0"
			(at 199.39 232.41 0)
			(effects
				(font
					(size 1.27 1.27)
					(thickness 0.15)
				)
				(justify left bottom)
				(hide yes)
			)
		)
		(property "Author" "Antmicro"
			(at 199.39 234.95 0)
			(effects
				(font
					(size 1.27 1.27)
					(thickness 0.15)
				)
				(justify left bottom)
				(hide yes)
			)
		)
		(property "Tolerance" "1%"
			(at 199.39 217.17 0)
			(effects
				(font
					(size 1.27 1.27)
				)
				(justify left bottom)
				(hide yes)
			)
		)
		(pin "1"
		)
		(pin "2"
		)
		(instances
			(project "jetson-agx-thor-baseboard"
				(path ""
					(reference "R140")
					(unit 1)
				)
			)
		)
	)
	(symbol
		(lib_id "antmicropower:GND")
		(at 72.39 110.49 0)
		(mirror y)
		(unit 1)
		(exclude_from_sim no)
		(in_bom yes)
		(on_board yes)
		(dnp no)
		(property "Reference" "#PWR0234"
			(at 72.39 116.84 0)
			(effects
				(font
					(size 1.27 1.27)
				)
				(justify left bottom)
				(hide yes)
			)
		)
		(property "Value" "GND"
			(at 72.39 114.3 0)
			(effects
				(font
					(size 1.27 1.27)
					(thickness 0.15)
				)
			)
		)
		(property "Footprint" ""
			(at 63.5 118.11 0)
			(effects
				(font
					(size 1.27 1.27)
					(thickness 0.15)
				)
				(justify left bottom)
				(hide yes)
			)
		)
		(property "Datasheet" ""
			(at 63.5 123.19 0)
			(effects
				(font
					(size 1.27 1.27)
					(thickness 0.15)
				)
				(justify left bottom)
				(hide yes)
			)
		)
		(property "Description" ""
			(at 72.39 110.49 0)
			(effects
				(font
					(size 1.27 1.27)
				)
				(hide yes)
			)
		)
		(property "Author" "Antmicro"
			(at 63.5 118.11 0)
			(effects
				(font
					(size 1.27 1.27)
					(thickness 0.15)
				)
				(justify left bottom)
				(hide yes)
			)
		)
		(property "License" "Apache-2.0"
			(at 63.5 120.65 0)
			(effects
				(font
					(size 1.27 1.27)
					(thickness 0.15)
				)
				(justify left bottom)
				(hide yes)
			)
		)
		(pin "1"
		)
		(instances
			(project "jetson-agx-thor-baseboard"
				(path ""
					(reference "#PWR0234")
					(unit 1)
				)
			)
		)
	)
	(symbol
		(lib_id "antmicropower:GND")
		(at 288.29 177.8 0)
		(mirror y)
		(unit 1)
		(exclude_from_sim no)
		(in_bom yes)
		(on_board yes)
		(dnp no)
		(property "Reference" "#PWR0282"
			(at 288.29 184.15 0)
			(effects
				(font
					(size 1.27 1.27)
				)
				(justify left bottom)
				(hide yes)
			)
		)
		(property "Value" "GND"
			(at 288.29 181.61 0)
			(effects
				(font
					(size 1.27 1.27)
					(thickness 0.15)
				)
			)
		)
		(property "Footprint" ""
			(at 279.4 185.42 0)
			(effects
				(font
					(size 1.27 1.27)
					(thickness 0.15)
				)
				(justify left bottom)
				(hide yes)
			)
		)
		(property "Datasheet" ""
			(at 279.4 190.5 0)
			(effects
				(font
					(size 1.27 1.27)
					(thickness 0.15)
				)
				(justify left bottom)
				(hide yes)
			)
		)
		(property "Description" ""
			(at 288.29 177.8 0)
			(effects
				(font
					(size 1.27 1.27)
				)
				(hide yes)
			)
		)
		(property "Author" "Antmicro"
			(at 279.4 185.42 0)
			(effects
				(font
					(size 1.27 1.27)
					(thickness 0.15)
				)
				(justify left bottom)
				(hide yes)
			)
		)
		(property "License" "Apache-2.0"
			(at 279.4 187.96 0)
			(effects
				(font
					(size 1.27 1.27)
					(thickness 0.15)
				)
				(justify left bottom)
				(hide yes)
			)
		)
		(pin "1"
		)
		(instances
			(project "jetson-agx-thor-baseboard"
				(path ""
					(reference "#PWR0282")
					(unit 1)
				)
			)
		)
	)
	(symbol
		(lib_id "antmicroResistors0402:R_10k_0402")
		(at 180.34 55.88 90)
		(unit 1)
		(exclude_from_sim no)
		(in_bom yes)
		(on_board yes)
		(dnp no)
		(property "Reference" "R127"
			(at 181.61 52.07 90)
			(effects
				(font
					(size 1.27 1.27)
				)
				(justify right)
			)
		)
		(property "Value" "R_10k_0402"
			(at 193.04 35.56 0)
			(effects
				(font
					(size 1.27 1.27)
					(thickness 0.15)
				)
				(justify left bottom)
				(hide yes)
			)
		)
		(property "Footprint" "antmicro-footprints:R_0402_1005Metric"
			(at 195.58 35.56 0)
			(effects
				(font
					(size 1.27 1.27)
					(thickness 0.15)
				)
				(justify left bottom)
				(hide yes)
			)
		)
		(property "Datasheet" "https://www.bourns.com/docs/product-datasheets/cr.pdf"
			(at 198.12 35.56 0)
			(effects
				(font
					(size 1.27 1.27)
					(thickness 0.15)
				)
				(justify left bottom)
				(hide yes)
			)
		)
		(property "Description" "SMD Chip Resistor, 10 kohm, ± 1%, 62.5 mW, 0402 [1005 Metric], Thick Film, General Purpose"
			(at 180.34 55.88 0)
			(effects
				(font
					(size 1.27 1.27)
				)
				(hide yes)
			)
		)
		(property "Manufacturer" "Bourns"
			(at 203.2 35.56 0)
			(effects
				(font
					(size 1.27 1.27)
					(thickness 0.15)
				)
				(justify left bottom)
				(hide yes)
			)
		)
		(property "MPN" "CR0402-FX-1002GLF"
			(at 200.66 35.56 0)
			(effects
				(font
					(size 1.27 1.27)
					(thickness 0.15)
				)
				(justify left bottom)
				(hide yes)
			)
		)
		(property "Val" "10k"
			(at 181.61 54.61 90)
			(effects
				(font
					(size 1.27 1.27)
					(thickness 0.15)
				)
				(justify right)
			)
		)
		(property "License" "Apache-2.0"
			(at 205.74 35.56 0)
			(effects
				(font
					(size 1.27 1.27)
					(thickness 0.15)
				)
				(justify left bottom)
				(hide yes)
			)
		)
		(property "Author" "Antmicro"
			(at 208.28 35.56 0)
			(effects
				(font
					(size 1.27 1.27)
					(thickness 0.15)
				)
				(justify left bottom)
				(hide yes)
			)
		)
		(property "Tolerance" "1%"
			(at 190.5 35.56 0)
			(effects
				(font
					(size 1.27 1.27)
				)
				(justify left bottom)
				(hide yes)
			)
		)
		(pin "1"
		)
		(pin "2"
		)
		(instances
			(project "jetson-agx-thor-baseboard"
				(path ""
					(reference "R127")
					(unit 1)
				)
			)
		)
	)
	(symbol
		(lib_id "antmicropower:GND")
		(at 212.09 173.99 0)
		(mirror y)
		(unit 1)
		(exclude_from_sim no)
		(in_bom yes)
		(on_board yes)
		(dnp no)
		(property "Reference" "#PWR0267"
			(at 212.09 180.34 0)
			(effects
				(font
					(size 1.27 1.27)
				)
				(justify left bottom)
				(hide yes)
			)
		)
		(property "Value" "GND"
			(at 212.09 177.8 0)
			(effects
				(font
					(size 1.27 1.27)
					(thickness 0.15)
				)
			)
		)
		(property "Footprint" ""
			(at 203.2 181.61 0)
			(effects
				(font
					(size 1.27 1.27)
					(thickness 0.15)
				)
				(justify left bottom)
				(hide yes)
			)
		)
		(property "Datasheet" ""
			(at 203.2 186.69 0)
			(effects
				(font
					(size 1.27 1.27)
					(thickness 0.15)
				)
				(justify left bottom)
				(hide yes)
			)
		)
		(property "Description" ""
			(at 212.09 173.99 0)
			(effects
				(font
					(size 1.27 1.27)
				)
				(hide yes)
			)
		)
		(property "Author" "Antmicro"
			(at 203.2 181.61 0)
			(effects
				(font
					(size 1.27 1.27)
					(thickness 0.15)
				)
				(justify left bottom)
				(hide yes)
			)
		)
		(property "License" "Apache-2.0"
			(at 203.2 184.15 0)
			(effects
				(font
					(size 1.27 1.27)
					(thickness 0.15)
				)
				(justify left bottom)
				(hide yes)
			)
		)
		(pin "1"
		)
		(instances
			(project "jetson-agx-thor-baseboard"
				(path ""
					(reference "#PWR0267")
					(unit 1)
				)
			)
		)
	)
	(symbol
		(lib_id "antmicropower:GND")
		(at 115.57 110.49 0)
		(mirror y)
		(unit 1)
		(exclude_from_sim no)
		(in_bom yes)
		(on_board yes)
		(dnp no)
		(property "Reference" "#PWR0243"
			(at 115.57 116.84 0)
			(effects
				(font
					(size 1.27 1.27)
				)
				(justify left bottom)
				(hide yes)
			)
		)
		(property "Value" "GND"
			(at 115.57 114.3 0)
			(effects
				(font
					(size 1.27 1.27)
					(thickness 0.15)
				)
			)
		)
		(property "Footprint" ""
			(at 106.68 118.11 0)
			(effects
				(font
					(size 1.27 1.27)
					(thickness 0.15)
				)
				(justify left bottom)
				(hide yes)
			)
		)
		(property "Datasheet" ""
			(at 106.68 123.19 0)
			(effects
				(font
					(size 1.27 1.27)
					(thickness 0.15)
				)
				(justify left bottom)
				(hide yes)
			)
		)
		(property "Description" ""
			(at 115.57 110.49 0)
			(effects
				(font
					(size 1.27 1.27)
				)
				(hide yes)
			)
		)
		(property "Author" "Antmicro"
			(at 106.68 118.11 0)
			(effects
				(font
					(size 1.27 1.27)
					(thickness 0.15)
				)
				(justify left bottom)
				(hide yes)
			)
		)
		(property "License" "Apache-2.0"
			(at 106.68 120.65 0)
			(effects
				(font
					(size 1.27 1.27)
					(thickness 0.15)
				)
				(justify left bottom)
				(hide yes)
			)
		)
		(pin "1"
		)
		(instances
			(project "jetson-agx-thor-baseboard"
				(path ""
					(reference "#PWR0243")
					(unit 1)
				)
			)
		)
	)
	(symbol
		(lib_id "antmicropower:+5V")
		(at 189.23 48.26 0)
		(unit 1)
		(exclude_from_sim no)
		(in_bom yes)
		(on_board yes)
		(dnp no)
		(property "Reference" "#PWR0250"
			(at 189.23 52.07 0)
			(effects
				(font
					(size 1.27 1.27)
				)
				(justify left bottom)
				(hide yes)
			)
		)
		(property "Value" "+5V"
			(at 187.325 45.085 0)
			(effects
				(font
					(size 1.27 1.27)
					(thickness 0.15)
				)
				(justify left bottom)
			)
		)
		(property "Footprint" ""
			(at 204.47 55.88 0)
			(effects
				(font
					(size 1.27 1.27)
					(thickness 0.15)
				)
				(justify left bottom)
				(hide yes)
			)
		)
		(property "Datasheet" ""
			(at 204.47 58.42 0)
			(effects
				(font
					(size 1.27 1.27)
					(thickness 0.15)
				)
				(justify left bottom)
				(hide yes)
			)
		)
		(property "Description" ""
			(at 189.23 48.26 0)
			(effects
				(font
					(size 1.27 1.27)
				)
				(hide yes)
			)
		)
		(property "Author" "Antmicro"
			(at 204.47 55.88 0)
			(effects
				(font
					(size 1.27 1.27)
					(thickness 0.15)
				)
				(justify left bottom)
				(hide yes)
			)
		)
		(property "License" "Apache-2.0"
			(at 204.47 58.42 0)
			(effects
				(font
					(size 1.27 1.27)
					(thickness 0.15)
				)
				(justify left bottom)
				(hide yes)
			)
		)
		(pin "1"
		)
		(instances
			(project "jetson-agx-thor-baseboard"
				(path ""
					(reference "#PWR0250")
					(unit 1)
				)
			)
		)
	)
	(symbol
		(lib_id "antmicropower:+1V8")
		(at 116.84 220.98 0)
		(unit 1)
		(exclude_from_sim no)
		(in_bom yes)
		(on_board yes)
		(dnp no)
		(property "Reference" "#PWR0638"
			(at 116.84 224.79 0)
			(effects
				(font
					(size 1.27 1.27)
				)
				(justify left bottom)
				(hide yes)
			)
		)
		(property "Value" "+1V8"
			(at 113.665 217.17 0)
			(effects
				(font
					(size 1.27 1.27)
					(thickness 0.15)
				)
				(justify left)
			)
		)
		(property "Footprint" ""
			(at 132.08 228.6 0)
			(effects
				(font
					(size 1.27 1.27)
					(thickness 0.15)
				)
				(justify left bottom)
				(hide yes)
			)
		)
		(property "Datasheet" ""
			(at 132.08 231.14 0)
			(effects
				(font
					(size 1.27 1.27)
					(thickness 0.15)
				)
				(justify left bottom)
				(hide yes)
			)
		)
		(property "Description" ""
			(at 116.84 220.98 0)
			(effects
				(font
					(size 1.27 1.27)
				)
				(hide yes)
			)
		)
		(property "Author" "Antmicro"
			(at 132.08 226.06 0)
			(effects
				(font
					(size 1.27 1.27)
					(thickness 0.15)
				)
				(justify left bottom)
				(hide yes)
			)
		)
		(property "License" "Apache-2.0"
			(at 132.08 228.6 0)
			(effects
				(font
					(size 1.27 1.27)
					(thickness 0.15)
				)
				(justify left bottom)
				(hide yes)
			)
		)
		(pin "1"
		)
		(instances
			(project "jetson-agx-thor-baseboard"
				(path ""
					(reference "#PWR0638")
					(unit 1)
				)
			)
		)
	)
	(symbol
		(lib_id "antmicropower:GND")
		(at 294.64 179.07 0)
		(mirror y)
		(unit 1)
		(exclude_from_sim no)
		(in_bom yes)
		(on_board yes)
		(dnp no)
		(property "Reference" "#PWR0284"
			(at 294.64 185.42 0)
			(effects
				(font
					(size 1.27 1.27)
				)
				(justify left bottom)
				(hide yes)
			)
		)
		(property "Value" "GND"
			(at 294.64 182.88 0)
			(effects
				(font
					(size 1.27 1.27)
					(thickness 0.15)
				)
			)
		)
		(property "Footprint" ""
			(at 285.75 186.69 0)
			(effects
				(font
					(size 1.27 1.27)
					(thickness 0.15)
				)
				(justify left bottom)
				(hide yes)
			)
		)
		(property "Datasheet" ""
			(at 285.75 191.77 0)
			(effects
				(font
					(size 1.27 1.27)
					(thickness 0.15)
				)
				(justify left bottom)
				(hide yes)
			)
		)
		(property "Description" ""
			(at 294.64 179.07 0)
			(effects
				(font
					(size 1.27 1.27)
				)
				(hide yes)
			)
		)
		(property "Author" "Antmicro"
			(at 285.75 186.69 0)
			(effects
				(font
					(size 1.27 1.27)
					(thickness 0.15)
				)
				(justify left bottom)
				(hide yes)
			)
		)
		(property "License" "Apache-2.0"
			(at 285.75 189.23 0)
			(effects
				(font
					(size 1.27 1.27)
					(thickness 0.15)
				)
				(justify left bottom)
				(hide yes)
			)
		)
		(pin "1"
		)
		(instances
			(project "jetson-agx-thor-baseboard"
				(path ""
					(reference "#PWR0284")
					(unit 1)
				)
			)
		)
	)
	(symbol
		(lib_id "antmicropower:GND")
		(at 152.4 210.82 0)
		(mirror y)
		(unit 1)
		(exclude_from_sim no)
		(in_bom yes)
		(on_board yes)
		(dnp no)
		(property "Reference" "#PWR0248"
			(at 152.4 217.17 0)
			(effects
				(font
					(size 1.27 1.27)
				)
				(justify left bottom)
				(hide yes)
			)
		)
		(property "Value" "GND"
			(at 152.4 214.63 0)
			(effects
				(font
					(size 1.27 1.27)
					(thickness 0.15)
				)
			)
		)
		(property "Footprint" ""
			(at 143.51 218.44 0)
			(effects
				(font
					(size 1.27 1.27)
					(thickness 0.15)
				)
				(justify left bottom)
				(hide yes)
			)
		)
		(property "Datasheet" ""
			(at 143.51 223.52 0)
			(effects
				(font
					(size 1.27 1.27)
					(thickness 0.15)
				)
				(justify left bottom)
				(hide yes)
			)
		)
		(property "Description" ""
			(at 152.4 210.82 0)
			(effects
				(font
					(size 1.27 1.27)
				)
				(hide yes)
			)
		)
		(property "Author" "Antmicro"
			(at 143.51 218.44 0)
			(effects
				(font
					(size 1.27 1.27)
					(thickness 0.15)
				)
				(justify left bottom)
				(hide yes)
			)
		)
		(property "License" "Apache-2.0"
			(at 143.51 220.98 0)
			(effects
				(font
					(size 1.27 1.27)
					(thickness 0.15)
				)
				(justify left bottom)
				(hide yes)
			)
		)
		(pin "1"
		)
		(instances
			(project "jetson-agx-thor-baseboard"
				(path ""
					(reference "#PWR0248")
					(unit 1)
				)
			)
		)
	)
	(symbol
		(lib_id "antmicropower:GND")
		(at 116.84 241.3 0)
		(mirror y)
		(unit 1)
		(exclude_from_sim no)
		(in_bom yes)
		(on_board yes)
		(dnp no)
		(property "Reference" "#PWR0639"
			(at 116.84 247.65 0)
			(effects
				(font
					(size 1.27 1.27)
				)
				(justify left bottom)
				(hide yes)
			)
		)
		(property "Value" "GND"
			(at 116.84 245.11 0)
			(effects
				(font
					(size 1.27 1.27)
					(thickness 0.15)
				)
			)
		)
		(property "Footprint" ""
			(at 107.95 248.92 0)
			(effects
				(font
					(size 1.27 1.27)
					(thickness 0.15)
				)
				(justify left bottom)
				(hide yes)
			)
		)
		(property "Datasheet" ""
			(at 107.95 254 0)
			(effects
				(font
					(size 1.27 1.27)
					(thickness 0.15)
				)
				(justify left bottom)
				(hide yes)
			)
		)
		(property "Description" ""
			(at 116.84 241.3 0)
			(effects
				(font
					(size 1.27 1.27)
				)
				(hide yes)
			)
		)
		(property "Author" "Antmicro"
			(at 107.95 248.92 0)
			(effects
				(font
					(size 1.27 1.27)
					(thickness 0.15)
				)
				(justify left bottom)
				(hide yes)
			)
		)
		(property "License" "Apache-2.0"
			(at 107.95 251.46 0)
			(effects
				(font
					(size 1.27 1.27)
					(thickness 0.15)
				)
				(justify left bottom)
				(hide yes)
			)
		)
		(pin "1"
		)
		(instances
			(project "jetson-agx-thor-baseboard"
				(path ""
					(reference "#PWR0639")
					(unit 1)
				)
			)
		)
	)
	(symbol
		(lib_id "antmicropower:GND")
		(at 190.5 210.82 0)
		(mirror y)
		(unit 1)
		(exclude_from_sim no)
		(in_bom yes)
		(on_board yes)
		(dnp no)
		(property "Reference" "#PWR0256"
			(at 190.5 217.17 0)
			(effects
				(font
					(size 1.27 1.27)
				)
				(justify left bottom)
				(hide yes)
			)
		)
		(property "Value" "GND"
			(at 190.5 214.63 0)
			(effects
				(font
					(size 1.27 1.27)
					(thickness 0.15)
				)
			)
		)
		(property "Footprint" ""
			(at 181.61 218.44 0)
			(effects
				(font
					(size 1.27 1.27)
					(thickness 0.15)
				)
				(justify left bottom)
				(hide yes)
			)
		)
		(property "Datasheet" ""
			(at 181.61 223.52 0)
			(effects
				(font
					(size 1.27 1.27)
					(thickness 0.15)
				)
				(justify left bottom)
				(hide yes)
			)
		)
		(property "Description" ""
			(at 190.5 210.82 0)
			(effects
				(font
					(size 1.27 1.27)
				)
				(hide yes)
			)
		)
		(property "Author" "Antmicro"
			(at 181.61 218.44 0)
			(effects
				(font
					(size 1.27 1.27)
					(thickness 0.15)
				)
				(justify left bottom)
				(hide yes)
			)
		)
		(property "License" "Apache-2.0"
			(at 181.61 220.98 0)
			(effects
				(font
					(size 1.27 1.27)
					(thickness 0.15)
				)
				(justify left bottom)
				(hide yes)
			)
		)
		(pin "1"
		)
		(instances
			(project "jetson-agx-thor-baseboard"
				(path ""
					(reference "#PWR0256")
					(unit 1)
				)
			)
		)
	)
	(symbol
		(lib_id "antmicroResistors0402:R_10k_0402")
		(at 116.84 227.33 90)
		(unit 1)
		(exclude_from_sim no)
		(in_bom yes)
		(on_board yes)
		(dnp no)
		(fields_autoplaced yes)
		(property "Reference" "R273"
			(at 119.38 223.52 90)
			(effects
				(font
					(size 1.27 1.27)
					(thickness 0.15)
				)
				(justify right)
			)
		)
		(property "Value" "R_10k_0402"
			(at 129.54 207.01 0)
			(effects
				(font
					(size 1.27 1.27)
					(thickness 0.15)
				)
				(justify left bottom)
				(hide yes)
			)
		)
		(property "Footprint" "antmicro-footprints:R_0402_1005Metric"
			(at 132.08 207.01 0)
			(effects
				(font
					(size 1.27 1.27)
					(thickness 0.15)
				)
				(justify left bottom)
				(hide yes)
			)
		)
		(property "Datasheet" "https://www.bourns.com/docs/product-datasheets/cr.pdf"
			(at 134.62 207.01 0)
			(effects
				(font
					(size 1.27 1.27)
					(thickness 0.15)
				)
				(justify left bottom)
				(hide yes)
			)
		)
		(property "Description" "SMD Chip Resistor, 10 kohm, ± 1%, 62.5 mW, 0402 [1005 Metric], Thick Film, General Purpose"
			(at 147.32 207.01 0)
			(effects
				(font
					(size 1.27 1.27)
				)
				(justify left bottom)
				(hide yes)
			)
		)
		(property "MPN" "CR0402-FX-1002GLF"
			(at 137.16 207.01 0)
			(effects
				(font
					(size 1.27 1.27)
					(thickness 0.15)
				)
				(justify left bottom)
				(hide yes)
			)
		)
		(property "Manufacturer" "Bourns"
			(at 139.7 207.01 0)
			(effects
				(font
					(size 1.27 1.27)
					(thickness 0.15)
				)
				(justify left bottom)
				(hide yes)
			)
		)
		(property "License" "Apache-2.0"
			(at 142.24 207.01 0)
			(effects
				(font
					(size 1.27 1.27)
					(thickness 0.15)
				)
				(justify left bottom)
				(hide yes)
			)
		)
		(property "Author" "Antmicro"
			(at 144.78 207.01 0)
			(effects
				(font
					(size 1.27 1.27)
					(thickness 0.15)
				)
				(justify left bottom)
				(hide yes)
			)
		)
		(property "Val" "10k"
			(at 119.38 226.06 90)
			(effects
				(font
					(size 1.27 1.27)
					(thickness 0.15)
				)
				(justify right)
			)
		)
		(property "Tolerance" "1%"
			(at 127 207.01 0)
			(effects
				(font
					(size 1.27 1.27)
				)
				(justify left bottom)
				(hide yes)
			)
		)
		(pin "1"
		)
		(pin "2"
		)
		(instances
			(project ""
				(path ""
					(reference "R273")
					(unit 1)
				)
			)
		)
	)
	(symbol
		(lib_id "antmicroCapacitors0402:C_100n_0402")
		(at 93.98 104.14 90)
		(mirror x)
		(unit 1)
		(exclude_from_sim no)
		(in_bom yes)
		(on_board yes)
		(dnp no)
		(fields_autoplaced yes)
		(property "Reference" "C126"
			(at 96.52 105.4163 90)
			(effects
				(font
					(size 1.27 1.27)
				)
				(justify right)
			)
		)
		(property "Value" "C_100n_0402"
			(at 104.14 124.46 0)
			(effects
				(font
					(size 1.27 1.27)
					(thickness 0.15)
				)
				(justify left bottom)
				(hide yes)
			)
		)
		(property "Footprint" "antmicro-footprints:C_0402_1005Metric"
			(at 106.68 124.46 0)
			(effects
				(font
					(size 1.27 1.27)
					(thickness 0.15)
				)
				(justify left bottom)
				(hide yes)
			)
		)
		(property "Datasheet" "https://www.murata.com/products/productdetail?partno=GRM155R61H104KE14%23"
			(at 109.22 124.46 0)
			(effects
				(font
					(size 1.27 1.27)
					(thickness 0.15)
				)
				(justify left bottom)
				(hide yes)
			)
		)
		(property "Description" "SMD Multilayer Ceramic Capacitor, 0.1 µF, 50 V, 0402 [1005 Metric], ± 10%, X5R, GRM Series"
			(at 93.98 104.14 0)
			(effects
				(font
					(size 1.27 1.27)
				)
				(hide yes)
			)
		)
		(property "Manufacturer" "Murata"
			(at 114.3 124.46 0)
			(effects
				(font
					(size 1.27 1.27)
					(thickness 0.15)
				)
				(justify left bottom)
				(hide yes)
			)
		)
		(property "MPN" "GRM155R61H104KE14D"
			(at 111.76 124.46 0)
			(effects
				(font
					(size 1.27 1.27)
					(thickness 0.15)
				)
				(justify left bottom)
				(hide yes)
			)
		)
		(property "Val" "100n"
			(at 96.52 107.9563 90)
			(effects
				(font
					(size 1.27 1.27)
					(thickness 0.15)
				)
				(justify right)
			)
		)
		(property "License" "Apache-2.0"
			(at 116.84 124.46 0)
			(effects
				(font
					(size 1.27 1.27)
					(thickness 0.15)
				)
				(justify left bottom)
				(hide yes)
			)
		)
		(property "Author" "Antmicro"
			(at 119.38 124.46 0)
			(effects
				(font
					(size 1.27 1.27)
					(thickness 0.15)
				)
				(justify left bottom)
				(hide yes)
			)
		)
		(property "Voltage" "50V"
			(at 121.92 124.46 0)
			(effects
				(font
					(size 1.27 1.27)
				)
				(justify left bottom)
				(hide yes)
			)
		)
		(property "Dielectric" "X5R"
			(at 124.46 124.46 0)
			(effects
				(font
					(size 1.27 1.27)
				)
				(justify left bottom)
				(hide yes)
			)
		)
		(pin "1"
		)
		(pin "2"
		)
		(instances
			(project "jetson-agx-thor-baseboard"
				(path ""
					(reference "C126")
					(unit 1)
				)
			)
		)
	)
	(symbol
		(lib_id "antmicroTVSDiodes:TPD4E05U06QDQARQ1")
		(at 278.13 172.72 270)
		(unit 1)
		(exclude_from_sim no)
		(in_bom yes)
		(on_board yes)
		(dnp no)
		(fields_autoplaced yes)
		(property "Reference" "U41"
			(at 273.685 184.15 90)
			(effects
				(font
					(size 1.27 1.27)
				)
			)
		)
		(property "Value" "TPD4E05U06QDQARQ1"
			(at 267.97 196.85 0)
			(effects
				(font
					(size 1.27 1.27)
					(thickness 0.15)
				)
				(justify left bottom)
				(hide yes)
			)
		)
		(property "Footprint" "antmicro-footprints:USON-10_2.5x1mm_P0.5mm"
			(at 273.05 196.85 0)
			(effects
				(font
					(size 1.27 1.27)
					(thickness 0.15)
				)
				(justify left bottom)
				(hide yes)
			)
		)
		(property "Datasheet" "https://www.ti.com/lit/ds/symlink/tpd4e05u06-q1.pdf?HQS=dis-mous-null-mousermode-dsf-pf-null-wwe&ts=1663591265741&ref_url=https%253A%252F%252Fwww.mouser.com%252F"
			(at 270.51 196.85 0)
			(effects
				(font
					(size 1.27 1.27)
					(thickness 0.15)
				)
				(justify left bottom)
				(hide yes)
			)
		)
		(property "Description" "TVS diode array, 12 kV, USON-10, 5.5 V, 0.5 pF"
			(at 278.13 172.72 0)
			(effects
				(font
					(size 1.27 1.27)
				)
				(hide yes)
			)
		)
		(property "Manufacturer" "Texas Instruments"
			(at 265.43 196.85 0)
			(effects
				(font
					(size 1.27 1.27)
					(thickness 0.15)
				)
				(justify left bottom)
				(hide yes)
			)
		)
		(property "MPN" "TPD4E05U06QDQARQ1"
			(at 273.685 186.69 90)
			(effects
				(font
					(size 1.27 1.27)
					(thickness 0.15)
				)
			)
		)
		(property "Author" "Antmicro"
			(at 262.89 196.85 0)
			(effects
				(font
					(size 1.27 1.27)
					(thickness 0.15)
				)
				(justify left bottom)
				(hide yes)
			)
		)
		(property "License" "Apache-2.0"
			(at 260.35 196.85 0)
			(effects
				(font
					(size 1.27 1.27)
					(thickness 0.15)
				)
				(justify left bottom)
				(hide yes)
			)
		)
		(pin "1"
		)
		(pin "10"
		)
		(pin "2"
		)
		(pin "3"
		)
		(pin "4"
		)
		(pin "5"
		)
		(pin "6"
		)
		(pin "7"
		)
		(pin "8"
		)
		(pin "9"
		)
		(instances
			(project "jetson-agx-thor-baseboard"
				(path ""
					(reference "U41")
					(unit 1)
				)
			)
		)
	)
	(symbol
		(lib_id "antmicroResistors0402:R_0R_0402")
		(at 194.31 68.58 0)
		(unit 1)
		(exclude_from_sim no)
		(in_bom yes)
		(on_board yes)
		(dnp no)
		(property "Reference" "R143"
			(at 199.39 67.945 0)
			(effects
				(font
					(size 1.27 1.27)
				)
				(justify left bottom)
			)
		)
		(property "Value" "R_0R_0402"
			(at 214.63 81.28 0)
			(effects
				(font
					(size 1.27 1.27)
					(thickness 0.15)
				)
				(justify left bottom)
				(hide yes)
			)
		)
		(property "Footprint" "antmicro-footprints:R_0402_1005Metric"
			(at 214.63 83.82 0)
			(effects
				(font
					(size 1.27 1.27)
					(thickness 0.15)
				)
				(justify left bottom)
				(hide yes)
			)
		)
		(property "Datasheet" "https://industrial.panasonic.com/cdbs/www-data/pdf/RDA0000/AOA0000C301.pdf"
			(at 214.63 86.36 0)
			(effects
				(font
					(size 1.27 1.27)
					(thickness 0.15)
				)
				(justify left bottom)
				(hide yes)
			)
		)
		(property "Description" "SMD Chip Resistor, Jumper, 0 ohm, 100 mW, 0402 [1005 Metric], Thick Film, General Purpose"
			(at 194.31 68.58 0)
			(effects
				(font
					(size 1.27 1.27)
				)
				(hide yes)
			)
		)
		(property "Manufacturer" "Panasonic"
			(at 214.63 91.44 0)
			(effects
				(font
					(size 1.27 1.27)
					(thickness 0.15)
				)
				(justify left bottom)
				(hide yes)
			)
		)
		(property "MPN" "ERJ2GE0R00X"
			(at 214.63 88.9 0)
			(effects
				(font
					(size 1.27 1.27)
					(thickness 0.15)
				)
				(justify left bottom)
				(hide yes)
			)
		)
		(property "Val" "0R"
			(at 191.77 67.945 0)
			(effects
				(font
					(size 1.27 1.27)
					(thickness 0.15)
				)
				(justify left bottom)
			)
		)
		(property "License" "Apache-2.0"
			(at 214.63 93.98 0)
			(effects
				(font
					(size 1.27 1.27)
					(thickness 0.15)
				)
				(justify left bottom)
				(hide yes)
			)
		)
		(property "Author" "Antmicro"
			(at 214.63 96.52 0)
			(effects
				(font
					(size 1.27 1.27)
					(thickness 0.15)
				)
				(justify left bottom)
				(hide yes)
			)
		)
		(property "Tolerance" "~"
			(at 214.63 78.74 0)
			(effects
				(font
					(size 1.27 1.27)
				)
				(justify left bottom)
				(hide yes)
			)
		)
		(property "Current" "1A"
			(at 214.63 99.06 0)
			(effects
				(font
					(size 1.27 1.27)
					(thickness 0.15)
				)
				(justify left bottom)
				(hide yes)
			)
		)
		(pin "1"
		)
		(pin "2"
		)
		(instances
			(project "jetson-agx-thor-baseboard"
				(path ""
					(reference "R143")
					(unit 1)
				)
			)
		)
	)
	(symbol
		(lib_id "antmicroCapacitorsmisc:C_22u_25V_0805")
		(at 287.02 64.77 90)
		(mirror x)
		(unit 1)
		(exclude_from_sim no)
		(in_bom yes)
		(on_board yes)
		(dnp no)
		(fields_autoplaced yes)
		(property "Reference" "C68"
			(at 289.56 66.0463 90)
			(effects
				(font
					(size 1.27 1.27)
				)
				(justify right)
			)
		)
		(property "Value" "C_22u_25V_0805"
			(at 297.18 85.09 0)
			(effects
				(font
					(size 1.27 1.27)
					(thickness 0.15)
				)
				(justify left bottom)
				(hide yes)
			)
		)
		(property "Footprint" "antmicro-footprints:C_0805_2012Metric"
			(at 299.72 85.09 0)
			(effects
				(font
					(size 1.27 1.27)
					(thickness 0.15)
				)
				(justify left bottom)
				(hide yes)
			)
		)
		(property "Datasheet" "https://product.samsungsem.com/mlcc/CL21A226MAYNNN.do"
			(at 302.26 85.09 0)
			(effects
				(font
					(size 1.27 1.27)
					(thickness 0.15)
				)
				(justify left bottom)
				(hide yes)
			)
		)
		(property "Description" "SMT Multilayer Ceramic Capacitor, 22uF, +/-20%, 25V, X5R, 0805 [2012 Metric]"
			(at 287.02 64.77 0)
			(effects
				(font
					(size 1.27 1.27)
				)
				(hide yes)
			)
		)
		(property "Manufacturer" "Samsung Electro-Mechanics"
			(at 307.34 85.09 0)
			(effects
				(font
					(size 1.27 1.27)
					(thickness 0.15)
				)
				(justify left bottom)
				(hide yes)
			)
		)
		(property "MPN" "CL21A226MAYNNNE"
			(at 304.8 85.09 0)
			(effects
				(font
					(size 1.27 1.27)
					(thickness 0.15)
				)
				(justify left bottom)
				(hide yes)
			)
		)
		(property "Val" "22u"
			(at 289.56 68.5863 90)
			(effects
				(font
					(size 1.27 1.27)
					(thickness 0.15)
				)
				(justify right)
			)
		)
		(property "License" "Apache-2.0"
			(at 309.88 85.09 0)
			(effects
				(font
					(size 1.27 1.27)
					(thickness 0.15)
				)
				(justify left bottom)
				(hide yes)
			)
		)
		(property "Author" "Antmicro"
			(at 312.42 85.09 0)
			(effects
				(font
					(size 1.27 1.27)
					(thickness 0.15)
				)
				(justify left bottom)
				(hide yes)
			)
		)
		(property "Voltage" "25V"
			(at 314.96 85.09 0)
			(effects
				(font
					(size 1.27 1.27)
				)
				(justify left bottom)
				(hide yes)
			)
		)
		(property "Dielectric" "X5R"
			(at 317.5 85.09 0)
			(effects
				(font
					(size 1.27 1.27)
				)
				(justify left bottom)
				(hide yes)
			)
		)
		(property "Public" "False"
			(at 320.04 85.09 0)
			(effects
				(font
					(size 1.27 1.27)
				)
				(justify left bottom)
				(hide yes)
			)
		)
		(pin "1"
		)
		(pin "2"
		)
		(instances
			(project "jetson-agx-thor-baseboard"
				(path ""
					(reference "C68")
					(unit 1)
				)
			)
		)
	)
	(symbol
		(lib_id "antmicropower:+5V")
		(at 187.96 113.03 0)
		(unit 1)
		(exclude_from_sim no)
		(in_bom yes)
		(on_board yes)
		(dnp no)
		(property "Reference" "#PWR0253"
			(at 187.96 116.84 0)
			(effects
				(font
					(size 1.27 1.27)
				)
				(justify left bottom)
				(hide yes)
			)
		)
		(property "Value" "+5V"
			(at 186.055 109.855 0)
			(effects
				(font
					(size 1.27 1.27)
					(thickness 0.15)
				)
				(justify left bottom)
			)
		)
		(property "Footprint" ""
			(at 203.2 120.65 0)
			(effects
				(font
					(size 1.27 1.27)
					(thickness 0.15)
				)
				(justify left bottom)
				(hide yes)
			)
		)
		(property "Datasheet" ""
			(at 203.2 123.19 0)
			(effects
				(font
					(size 1.27 1.27)
					(thickness 0.15)
				)
				(justify left bottom)
				(hide yes)
			)
		)
		(property "Description" ""
			(at 187.96 113.03 0)
			(effects
				(font
					(size 1.27 1.27)
				)
				(hide yes)
			)
		)
		(property "Author" "Antmicro"
			(at 203.2 120.65 0)
			(effects
				(font
					(size 1.27 1.27)
					(thickness 0.15)
				)
				(justify left bottom)
				(hide yes)
			)
		)
		(property "License" "Apache-2.0"
			(at 203.2 123.19 0)
			(effects
				(font
					(size 1.27 1.27)
					(thickness 0.15)
				)
				(justify left bottom)
				(hide yes)
			)
		)
		(pin "1"
		)
		(instances
			(project "jetson-agx-thor-baseboard"
				(path ""
					(reference "#PWR0253")
					(unit 1)
				)
			)
		)
	)
	(symbol
		(lib_id "antmicropower:GND")
		(at 177.8 101.6 0)
		(mirror y)
		(unit 1)
		(exclude_from_sim no)
		(in_bom yes)
		(on_board yes)
		(dnp no)
		(property "Reference" "#PWR0249"
			(at 177.8 107.95 0)
			(effects
				(font
					(size 1.27 1.27)
				)
				(justify left bottom)
				(hide yes)
			)
		)
		(property "Value" "GND"
			(at 177.8 105.41 0)
			(effects
				(font
					(size 1.27 1.27)
					(thickness 0.15)
				)
			)
		)
		(property "Footprint" ""
			(at 168.91 109.22 0)
			(effects
				(font
					(size 1.27 1.27)
					(thickness 0.15)
				)
				(justify left bottom)
				(hide yes)
			)
		)
		(property "Datasheet" ""
			(at 168.91 114.3 0)
			(effects
				(font
					(size 1.27 1.27)
					(thickness 0.15)
				)
				(justify left bottom)
				(hide yes)
			)
		)
		(property "Description" ""
			(at 177.8 101.6 0)
			(effects
				(font
					(size 1.27 1.27)
				)
				(hide yes)
			)
		)
		(property "Author" "Antmicro"
			(at 168.91 109.22 0)
			(effects
				(font
					(size 1.27 1.27)
					(thickness 0.15)
				)
				(justify left bottom)
				(hide yes)
			)
		)
		(property "License" "Apache-2.0"
			(at 168.91 111.76 0)
			(effects
				(font
					(size 1.27 1.27)
					(thickness 0.15)
				)
				(justify left bottom)
				(hide yes)
			)
		)
		(pin "1"
		)
		(instances
			(project "jetson-agx-thor-baseboard"
				(path ""
					(reference "#PWR0249")
					(unit 1)
				)
			)
		)
	)
	(symbol
		(lib_id "antmicroCapacitors0402:C_100n_0402")
		(at 176.53 161.29 0)
		(mirror x)
		(unit 1)
		(exclude_from_sim no)
		(in_bom yes)
		(on_board yes)
		(dnp no)
		(property "Reference" "C145"
			(at 185.166 160.02 0)
			(effects
				(font
					(size 1.27 1.27)
				)
				(justify right)
			)
		)
		(property "Value" "C_100n_0402"
			(at 196.85 151.13 0)
			(effects
				(font
					(size 1.27 1.27)
					(thickness 0.15)
				)
				(justify left bottom)
				(hide yes)
			)
		)
		(property "Footprint" "antmicro-footprints:C_0402_1005Metric"
			(at 196.85 148.59 0)
			(effects
				(font
					(size 1.27 1.27)
					(thickness 0.15)
				)
				(justify left bottom)
				(hide yes)
			)
		)
		(property "Datasheet" "https://www.murata.com/products/productdetail?partno=GRM155R61H104KE14%23"
			(at 196.85 146.05 0)
			(effects
				(font
					(size 1.27 1.27)
					(thickness 0.15)
				)
				(justify left bottom)
				(hide yes)
			)
		)
		(property "Description" "SMD Multilayer Ceramic Capacitor, 0.1 µF, 50 V, 0402 [1005 Metric], ± 10%, X5R, GRM Series"
			(at 176.53 161.29 0)
			(effects
				(font
					(size 1.27 1.27)
				)
				(hide yes)
			)
		)
		(property "Manufacturer" "Murata"
			(at 196.85 140.97 0)
			(effects
				(font
					(size 1.27 1.27)
					(thickness 0.15)
				)
				(justify left bottom)
				(hide yes)
			)
		)
		(property "MPN" "GRM155R61H104KE14D"
			(at 196.85 143.51 0)
			(effects
				(font
					(size 1.27 1.27)
					(thickness 0.15)
				)
				(justify left bottom)
				(hide yes)
			)
		)
		(property "Val" "100n"
			(at 178.054 162.56 0)
			(effects
				(font
					(size 1.27 1.27)
					(thickness 0.15)
				)
				(justify right)
			)
		)
		(property "License" "Apache-2.0"
			(at 196.85 138.43 0)
			(effects
				(font
					(size 1.27 1.27)
					(thickness 0.15)
				)
				(justify left bottom)
				(hide yes)
			)
		)
		(property "Author" "Antmicro"
			(at 196.85 135.89 0)
			(effects
				(font
					(size 1.27 1.27)
					(thickness 0.15)
				)
				(justify left bottom)
				(hide yes)
			)
		)
		(property "Voltage" "50V"
			(at 196.85 133.35 0)
			(effects
				(font
					(size 1.27 1.27)
				)
				(justify left bottom)
				(hide yes)
			)
		)
		(property "Dielectric" "X5R"
			(at 196.85 130.81 0)
			(effects
				(font
					(size 1.27 1.27)
				)
				(justify left bottom)
				(hide yes)
			)
		)
		(pin "1"
		)
		(pin "2"
		)
		(instances
			(project "jetson-agx-thor-baseboard"
				(path ""
					(reference "C145")
					(unit 1)
				)
			)
		)
	)
	(symbol
		(lib_id "antmicropower:GND")
		(at 278.13 99.06 0)
		(mirror y)
		(unit 1)
		(exclude_from_sim no)
		(in_bom yes)
		(on_board yes)
		(dnp no)
		(property "Reference" "#PWR0268"
			(at 278.13 105.41 0)
			(effects
				(font
					(size 1.27 1.27)
				)
				(justify left bottom)
				(hide yes)
			)
		)
		(property "Value" "GND"
			(at 278.13 102.87 0)
			(effects
				(font
					(size 1.27 1.27)
					(thickness 0.15)
				)
			)
		)
		(property "Footprint" ""
			(at 269.24 106.68 0)
			(effects
				(font
					(size 1.27 1.27)
					(thickness 0.15)
				)
				(justify left bottom)
				(hide yes)
			)
		)
		(property "Datasheet" ""
			(at 269.24 111.76 0)
			(effects
				(font
					(size 1.27 1.27)
					(thickness 0.15)
				)
				(justify left bottom)
				(hide yes)
			)
		)
		(property "Description" ""
			(at 278.13 99.06 0)
			(effects
				(font
					(size 1.27 1.27)
				)
				(hide yes)
			)
		)
		(property "Author" "Antmicro"
			(at 269.24 106.68 0)
			(effects
				(font
					(size 1.27 1.27)
					(thickness 0.15)
				)
				(justify left bottom)
				(hide yes)
			)
		)
		(property "License" "Apache-2.0"
			(at 269.24 109.22 0)
			(effects
				(font
					(size 1.27 1.27)
					(thickness 0.15)
				)
				(justify left bottom)
				(hide yes)
			)
		)
		(pin "1"
		)
		(instances
			(project "jetson-agx-thor-baseboard"
				(path ""
					(reference "#PWR0268")
					(unit 1)
				)
			)
		)
	)
	(symbol
		(lib_id "antmicroCapacitors0402:C_100n_0402")
		(at 198.12 50.8 90)
		(mirror x)
		(unit 1)
		(exclude_from_sim no)
		(in_bom yes)
		(on_board yes)
		(dnp no)
		(property "Reference" "C137"
			(at 200.025 52.07 90)
			(effects
				(font
					(size 1.27 1.27)
				)
				(justify right)
			)
		)
		(property "Value" "C_100n_0402"
			(at 208.28 71.12 0)
			(effects
				(font
					(size 1.27 1.27)
					(thickness 0.15)
				)
				(justify left bottom)
				(hide yes)
			)
		)
		(property "Footprint" "antmicro-footprints:C_0402_1005Metric"
			(at 210.82 71.12 0)
			(effects
				(font
					(size 1.27 1.27)
					(thickness 0.15)
				)
				(justify left bottom)
				(hide yes)
			)
		)
		(property "Datasheet" "https://www.murata.com/products/productdetail?partno=GRM155R61H104KE14%23"
			(at 213.36 71.12 0)
			(effects
				(font
					(size 1.27 1.27)
					(thickness 0.15)
				)
				(justify left bottom)
				(hide yes)
			)
		)
		(property "Description" "SMD Multilayer Ceramic Capacitor, 0.1 µF, 50 V, 0402 [1005 Metric], ± 10%, X5R, GRM Series"
			(at 198.12 50.8 0)
			(effects
				(font
					(size 1.27 1.27)
				)
				(hide yes)
			)
		)
		(property "Manufacturer" "Murata"
			(at 218.44 71.12 0)
			(effects
				(font
					(size 1.27 1.27)
					(thickness 0.15)
				)
				(justify left bottom)
				(hide yes)
			)
		)
		(property "MPN" "GRM155R61H104KE14D"
			(at 215.9 71.12 0)
			(effects
				(font
					(size 1.27 1.27)
					(thickness 0.15)
				)
				(justify left bottom)
				(hide yes)
			)
		)
		(property "Val" "100n"
			(at 200.025 54.61 90)
			(effects
				(font
					(size 1.27 1.27)
					(thickness 0.15)
				)
				(justify right)
			)
		)
		(property "License" "Apache-2.0"
			(at 220.98 71.12 0)
			(effects
				(font
					(size 1.27 1.27)
					(thickness 0.15)
				)
				(justify left bottom)
				(hide yes)
			)
		)
		(property "Author" "Antmicro"
			(at 223.52 71.12 0)
			(effects
				(font
					(size 1.27 1.27)
					(thickness 0.15)
				)
				(justify left bottom)
				(hide yes)
			)
		)
		(property "Voltage" "50V"
			(at 226.06 71.12 0)
			(effects
				(font
					(size 1.27 1.27)
				)
				(justify left bottom)
				(hide yes)
			)
		)
		(property "Dielectric" "X5R"
			(at 228.6 71.12 0)
			(effects
				(font
					(size 1.27 1.27)
				)
				(justify left bottom)
				(hide yes)
			)
		)
		(pin "1"
		)
		(pin "2"
		)
		(instances
			(project "jetson-agx-thor-baseboard"
				(path ""
					(reference "C137")
					(unit 1)
				)
			)
		)
	)
	(symbol
		(lib_id "antmicroCapacitors0402:C_100n_0402")
		(at 177.8 95.25 270)
		(unit 1)
		(exclude_from_sim no)
		(in_bom yes)
		(on_board yes)
		(dnp no)
		(fields_autoplaced yes)
		(property "Reference" "C136"
			(at 180.34 96.5263 90)
			(effects
				(font
					(size 1.27 1.27)
				)
				(justify left)
			)
		)
		(property "Value" "C_100n_0402"
			(at 167.64 115.57 0)
			(effects
				(font
					(size 1.27 1.27)
					(thickness 0.15)
				)
				(justify left bottom)
				(hide yes)
			)
		)
		(property "Footprint" "antmicro-footprints:C_0402_1005Metric"
			(at 165.1 115.57 0)
			(effects
				(font
					(size 1.27 1.27)
					(thickness 0.15)
				)
				(justify left bottom)
				(hide yes)
			)
		)
		(property "Datasheet" "https://www.murata.com/products/productdetail?partno=GRM155R61H104KE14%23"
			(at 162.56 115.57 0)
			(effects
				(font
					(size 1.27 1.27)
					(thickness 0.15)
				)
				(justify left bottom)
				(hide yes)
			)
		)
		(property "Description" "SMD Multilayer Ceramic Capacitor, 0.1 µF, 50 V, 0402 [1005 Metric], ± 10%, X5R, GRM Series"
			(at 177.8 95.25 0)
			(effects
				(font
					(size 1.27 1.27)
				)
				(hide yes)
			)
		)
		(property "MPN" "GRM155R61H104KE14D"
			(at 160.02 115.57 0)
			(effects
				(font
					(size 1.27 1.27)
					(thickness 0.15)
				)
				(justify left bottom)
				(hide yes)
			)
		)
		(property "Manufacturer" "Murata"
			(at 157.48 115.57 0)
			(effects
				(font
					(size 1.27 1.27)
					(thickness 0.15)
				)
				(justify left bottom)
				(hide yes)
			)
		)
		(property "Val" "100n"
			(at 180.34 99.0663 90)
			(effects
				(font
					(size 1.27 1.27)
					(thickness 0.15)
				)
				(justify left)
			)
		)
		(property "License" "Apache-2.0"
			(at 154.94 115.57 0)
			(effects
				(font
					(size 1.27 1.27)
					(thickness 0.15)
				)
				(justify left bottom)
				(hide yes)
			)
		)
		(property "Author" "Antmicro"
			(at 152.4 115.57 0)
			(effects
				(font
					(size 1.27 1.27)
					(thickness 0.15)
				)
				(justify left bottom)
				(hide yes)
			)
		)
		(property "Voltage" "50V"
			(at 149.86 115.57 0)
			(effects
				(font
					(size 1.27 1.27)
				)
				(justify left bottom)
				(hide yes)
			)
		)
		(property "Dielectric" "X5R"
			(at 147.32 115.57 0)
			(effects
				(font
					(size 1.27 1.27)
				)
				(justify left bottom)
				(hide yes)
			)
		)
		(pin "1"
		)
		(pin "2"
		)
		(instances
			(project "jetson-agx-thor-baseboard"
				(path ""
					(reference "C136")
					(unit 1)
				)
			)
		)
	)
	(symbol
		(lib_id "antmicroLEDIndicationDiscrete:LED_G_0603_LTST-C190GKT")
		(at 297.18 76.2 90)
		(unit 1)
		(exclude_from_sim no)
		(in_bom yes)
		(on_board yes)
		(dnp no)
		(property "Reference" "D25"
			(at 299.085 72.39 90)
			(effects
				(font
					(size 1.27 1.27)
				)
				(justify right)
			)
		)
		(property "Value" "LED_G_0603_LTST-C190GKT"
			(at 304.8 53.34 0)
			(effects
				(font
					(size 1.27 1.27)
					(thickness 0.15)
				)
				(justify left bottom)
				(hide yes)
			)
		)
		(property "Footprint" "antmicro-footprints:LED_0603_1608Metric_G"
			(at 307.34 53.34 0)
			(effects
				(font
					(size 1.27 1.27)
					(thickness 0.15)
				)
				(justify left bottom)
				(hide yes)
			)
		)
		(property "Datasheet" "https://media.digikey.com/pdf/Data%20Sheets/Lite-On%20PDFs/LTST-C190GKT.pdf"
			(at 309.88 53.34 0)
			(effects
				(font
					(size 1.27 1.27)
					(thickness 0.15)
				)
				(justify left bottom)
				(hide yes)
			)
		)
		(property "Description" "LED, Green, SMD, 0603, 20 mA, 2.1 V, 569 nm"
			(at 297.18 76.2 0)
			(effects
				(font
					(size 1.27 1.27)
				)
				(hide yes)
			)
		)
		(property "MPN" "LTST-C190GKT"
			(at 312.42 53.34 0)
			(effects
				(font
					(size 1.27 1.27)
					(thickness 0.15)
				)
				(justify left bottom)
				(hide yes)
			)
		)
		(property "Manufacturer" "Lite-On"
			(at 314.96 53.34 0)
			(effects
				(font
					(size 1.27 1.27)
					(thickness 0.15)
				)
				(justify left bottom)
				(hide yes)
			)
		)
		(property "Author" "Antmicro"
			(at 317.5 53.34 0)
			(effects
				(font
					(size 1.27 1.27)
					(thickness 0.15)
				)
				(justify left bottom)
				(hide yes)
			)
		)
		(property "License" "Apache-2.0"
			(at 320.04 53.34 0)
			(effects
				(font
					(size 1.27 1.27)
					(thickness 0.15)
				)
				(justify left bottom)
				(hide yes)
			)
		)
		(property "Color" "Green"
			(at 299.085 74.93 90)
			(effects
				(font
					(size 1.27 1.27)
				)
				(justify right)
			)
		)
		(pin "1"
		)
		(pin "2"
		)
		(instances
			(project "jetson-agx-thor-baseboard"
				(path ""
					(reference "D25")
					(unit 1)
				)
			)
		)
	)
	(symbol
		(lib_id "antmicroCapacitors0402:C_100n_0402")
		(at 115.57 104.14 90)
		(mirror x)
		(unit 1)
		(exclude_from_sim no)
		(in_bom yes)
		(on_board yes)
		(dnp no)
		(property "Reference" "C132"
			(at 118.11 105.4163 90)
			(effects
				(font
					(size 1.27 1.27)
				)
				(justify right)
			)
		)
		(property "Value" "C_100n_0402"
			(at 125.73 124.46 0)
			(effects
				(font
					(size 1.27 1.27)
					(thickness 0.15)
				)
				(justify left bottom)
				(hide yes)
			)
		)
		(property "Footprint" "antmicro-footprints:C_0402_1005Metric"
			(at 128.27 124.46 0)
			(effects
				(font
					(size 1.27 1.27)
					(thickness 0.15)
				)
				(justify left bottom)
				(hide yes)
			)
		)
		(property "Datasheet" "https://www.murata.com/products/productdetail?partno=GRM155R61H104KE14%23"
			(at 130.81 124.46 0)
			(effects
				(font
					(size 1.27 1.27)
					(thickness 0.15)
				)
				(justify left bottom)
				(hide yes)
			)
		)
		(property "Description" "SMD Multilayer Ceramic Capacitor, 0.1 µF, 50 V, 0402 [1005 Metric], ± 10%, X5R, GRM Series"
			(at 115.57 104.14 0)
			(effects
				(font
					(size 1.27 1.27)
				)
				(hide yes)
			)
		)
		(property "Manufacturer" "Murata"
			(at 135.89 124.46 0)
			(effects
				(font
					(size 1.27 1.27)
					(thickness 0.15)
				)
				(justify left bottom)
				(hide yes)
			)
		)
		(property "MPN" "GRM155R61H104KE14D"
			(at 133.35 124.46 0)
			(effects
				(font
					(size 1.27 1.27)
					(thickness 0.15)
				)
				(justify left bottom)
				(hide yes)
			)
		)
		(property "Val" "100n"
			(at 118.11 107.9563 90)
			(effects
				(font
					(size 1.27 1.27)
					(thickness 0.15)
				)
				(justify right)
			)
		)
		(property "License" "Apache-2.0"
			(at 138.43 124.46 0)
			(effects
				(font
					(size 1.27 1.27)
					(thickness 0.15)
				)
				(justify left bottom)
				(hide yes)
			)
		)
		(property "Author" "Antmicro"
			(at 140.97 124.46 0)
			(effects
				(font
					(size 1.27 1.27)
					(thickness 0.15)
				)
				(justify left bottom)
				(hide yes)
			)
		)
		(property "Voltage" "50V"
			(at 143.51 124.46 0)
			(effects
				(font
					(size 1.27 1.27)
				)
				(justify left bottom)
				(hide yes)
			)
		)
		(property "Dielectric" "X5R"
			(at 146.05 124.46 0)
			(effects
				(font
					(size 1.27 1.27)
				)
				(justify left bottom)
				(hide yes)
			)
		)
		(pin "1"
		)
		(pin "2"
		)
		(instances
			(project "jetson-agx-thor-baseboard"
				(path ""
					(reference "C132")
					(unit 1)
				)
			)
		)
	)
	(symbol
		(lib_id "antmicropower:+3V3")
		(at 90.17 173.99 0)
		(unit 1)
		(exclude_from_sim no)
		(in_bom yes)
		(on_board yes)
		(dnp no)
		(property "Reference" "#PWR0239"
			(at 90.17 177.8 0)
			(effects
				(font
					(size 1.27 1.27)
				)
				(justify left bottom)
				(hide yes)
			)
		)
		(property "Value" "+3V3"
			(at 86.995 170.18 0)
			(effects
				(font
					(size 1.27 1.27)
					(thickness 0.15)
				)
				(justify left)
			)
		)
		(property "Footprint" ""
			(at 105.41 181.61 0)
			(effects
				(font
					(size 1.27 1.27)
					(thickness 0.15)
				)
				(justify left bottom)
				(hide yes)
			)
		)
		(property "Datasheet" ""
			(at 105.41 184.15 0)
			(effects
				(font
					(size 1.27 1.27)
					(thickness 0.15)
				)
				(justify left bottom)
				(hide yes)
			)
		)
		(property "Description" ""
			(at 90.17 173.99 0)
			(effects
				(font
					(size 1.27 1.27)
				)
				(hide yes)
			)
		)
		(property "Author" "Antmicro"
			(at 105.41 176.53 0)
			(effects
				(font
					(size 1.27 1.27)
					(thickness 0.15)
				)
				(justify left bottom)
				(hide yes)
			)
		)
		(property "License" "Apache-2.0"
			(at 105.41 179.07 0)
			(effects
				(font
					(size 1.27 1.27)
					(thickness 0.15)
				)
				(justify left bottom)
				(hide yes)
			)
		)
		(pin "1"
		)
		(instances
			(project "jetson-agx-thor-baseboard"
				(path ""
					(reference "#PWR0239")
					(unit 1)
				)
			)
		)
	)
	(symbol
		(lib_id "antmicropower:+3V3")
		(at 72.39 101.6 0)
		(unit 1)
		(exclude_from_sim no)
		(in_bom yes)
		(on_board yes)
		(dnp no)
		(property "Reference" "#PWR0233"
			(at 72.39 105.41 0)
			(effects
				(font
					(size 1.27 1.27)
				)
				(justify left bottom)
				(hide yes)
			)
		)
		(property "Value" "+3V3"
			(at 69.215 97.79 0)
			(effects
				(font
					(size 1.27 1.27)
					(thickness 0.15)
				)
				(justify left)
			)
		)
		(property "Footprint" ""
			(at 87.63 109.22 0)
			(effects
				(font
					(size 1.27 1.27)
					(thickness 0.15)
				)
				(justify left bottom)
				(hide yes)
			)
		)
		(property "Datasheet" ""
			(at 87.63 111.76 0)
			(effects
				(font
					(size 1.27 1.27)
					(thickness 0.15)
				)
				(justify left bottom)
				(hide yes)
			)
		)
		(property "Description" ""
			(at 72.39 101.6 0)
			(effects
				(font
					(size 1.27 1.27)
				)
				(hide yes)
			)
		)
		(property "Author" "Antmicro"
			(at 87.63 104.14 0)
			(effects
				(font
					(size 1.27 1.27)
					(thickness 0.15)
				)
				(justify left bottom)
				(hide yes)
			)
		)
		(property "License" "Apache-2.0"
			(at 87.63 106.68 0)
			(effects
				(font
					(size 1.27 1.27)
					(thickness 0.15)
				)
				(justify left bottom)
				(hide yes)
			)
		)
		(pin "1"
		)
		(instances
			(project "jetson-agx-thor-baseboard"
				(path ""
					(reference "#PWR0233")
					(unit 1)
				)
			)
		)
	)
	(symbol
		(lib_id "antmicroResistors0402:R_1k_0402")
		(at 179.07 189.23 0)
		(unit 1)
		(exclude_from_sim no)
		(in_bom yes)
		(on_board yes)
		(dnp no)
		(property "Reference" "R133"
			(at 184.785 188.595 0)
			(effects
				(font
					(size 1.27 1.27)
				)
				(justify left bottom)
			)
		)
		(property "Value" "R_1k_0402"
			(at 199.39 201.93 0)
			(effects
				(font
					(size 1.27 1.27)
					(thickness 0.15)
				)
				(justify left bottom)
				(hide yes)
			)
		)
		(property "Footprint" "antmicro-footprints:R_0402_1005Metric"
			(at 199.39 204.47 0)
			(effects
				(font
					(size 1.27 1.27)
					(thickness 0.15)
				)
				(justify left bottom)
				(hide yes)
			)
		)
		(property "Datasheet" "https://www.bourns.com/docs/product-datasheets/cr.pdf"
			(at 199.39 207.01 0)
			(effects
				(font
					(size 1.27 1.27)
					(thickness 0.15)
				)
				(justify left bottom)
				(hide yes)
			)
		)
		(property "Description" "SMD Chip Resistor, 1 kohm, ± 1%, 63 mW, 0402 [1005 Metric], Thick Film, General Purpose"
			(at 179.07 189.23 0)
			(effects
				(font
					(size 1.27 1.27)
				)
				(hide yes)
			)
		)
		(property "Manufacturer" "Bourns"
			(at 199.39 212.09 0)
			(effects
				(font
					(size 1.27 1.27)
					(thickness 0.15)
				)
				(justify left bottom)
				(hide yes)
			)
		)
		(property "MPN" "CR0402-FX-1001GLF"
			(at 199.39 209.55 0)
			(effects
				(font
					(size 1.27 1.27)
					(thickness 0.15)
				)
				(justify left bottom)
				(hide yes)
			)
		)
		(property "Val" "1k"
			(at 176.53 188.595 0)
			(effects
				(font
					(size 1.27 1.27)
					(thickness 0.15)
				)
				(justify left bottom)
			)
		)
		(property "License" "Apache-2.0"
			(at 199.39 214.63 0)
			(effects
				(font
					(size 1.27 1.27)
					(thickness 0.15)
				)
				(justify left bottom)
				(hide yes)
			)
		)
		(property "Author" "Antmicro"
			(at 199.39 217.17 0)
			(effects
				(font
					(size 1.27 1.27)
					(thickness 0.15)
				)
				(justify left bottom)
				(hide yes)
			)
		)
		(property "Tolerance" "1%"
			(at 199.39 199.39 0)
			(effects
				(font
					(size 1.27 1.27)
				)
				(justify left bottom)
				(hide yes)
			)
		)
		(pin "1"
		)
		(pin "2"
		)
		(instances
			(project "jetson-agx-thor-baseboard"
				(path ""
					(reference "R133")
					(unit 1)
				)
			)
		)
	)
	(symbol
		(lib_id "antmicroResistors0402:R_0R_0402")
		(at 116.84 132.08 90)
		(unit 1)
		(exclude_from_sim no)
		(in_bom no)
		(on_board yes)
		(dnp yes)
		(property "Reference" "R121"
			(at 114.935 128.27 90)
			(effects
				(font
					(size 1.27 1.27)
				)
				(justify left)
			)
		)
		(property "Value" "R_0R_0402"
			(at 129.54 111.76 0)
			(effects
				(font
					(size 1.27 1.27)
					(thickness 0.15)
				)
				(justify left bottom)
				(hide yes)
			)
		)
		(property "Footprint" "antmicro-footprints:R_0402_1005Metric"
			(at 132.08 111.76 0)
			(effects
				(font
					(size 1.27 1.27)
					(thickness 0.15)
				)
				(justify left bottom)
				(hide yes)
			)
		)
		(property "Datasheet" "https://industrial.panasonic.com/cdbs/www-data/pdf/RDA0000/AOA0000C301.pdf"
			(at 134.62 111.76 0)
			(effects
				(font
					(size 1.27 1.27)
					(thickness 0.15)
				)
				(justify left bottom)
				(hide yes)
			)
		)
		(property "Description" "SMD Chip Resistor, Jumper, 0 ohm, 100 mW, 0402 [1005 Metric], Thick Film, General Purpose"
			(at 116.84 132.08 0)
			(effects
				(font
					(size 1.27 1.27)
				)
				(hide yes)
			)
		)
		(property "Manufacturer" "Panasonic"
			(at 139.7 111.76 0)
			(effects
				(font
					(size 1.27 1.27)
					(thickness 0.15)
				)
				(justify left bottom)
				(hide yes)
			)
		)
		(property "MPN" "ERJ2GE0R00X"
			(at 137.16 111.76 0)
			(effects
				(font
					(size 1.27 1.27)
					(thickness 0.15)
				)
				(justify left bottom)
				(hide yes)
			)
		)
		(property "Val" "0R"
			(at 114.935 130.81 90)
			(effects
				(font
					(size 1.27 1.27)
					(thickness 0.15)
				)
				(justify left)
			)
		)
		(property "License" "Apache-2.0"
			(at 142.24 111.76 0)
			(effects
				(font
					(size 1.27 1.27)
					(thickness 0.15)
				)
				(justify left bottom)
				(hide yes)
			)
		)
		(property "Author" "Antmicro"
			(at 144.78 111.76 0)
			(effects
				(font
					(size 1.27 1.27)
					(thickness 0.15)
				)
				(justify left bottom)
				(hide yes)
			)
		)
		(property "Tolerance" "~"
			(at 127 111.76 0)
			(effects
				(font
					(size 1.27 1.27)
				)
				(justify left bottom)
				(hide yes)
			)
		)
		(property "Current" "1A"
			(at 147.32 111.76 0)
			(effects
				(font
					(size 1.27 1.27)
					(thickness 0.15)
				)
				(justify left bottom)
				(hide yes)
			)
		)
		(pin "1"
		)
		(pin "2"
		)
		(instances
			(project "jetson-agx-thor-baseboard"
				(path ""
					(reference "R121")
					(unit 1)
				)
			)
		)
	)
	(symbol
		(lib_id "antmicropower:GND")
		(at 198.12 57.15 0)
		(mirror y)
		(unit 1)
		(exclude_from_sim no)
		(in_bom yes)
		(on_board yes)
		(dnp no)
		(property "Reference" "#PWR0251"
			(at 198.12 63.5 0)
			(effects
				(font
					(size 1.27 1.27)
				)
				(justify left bottom)
				(hide yes)
			)
		)
		(property "Value" "GND"
			(at 198.12 60.96 0)
			(effects
				(font
					(size 1.27 1.27)
					(thickness 0.15)
				)
			)
		)
		(property "Footprint" ""
			(at 189.23 64.77 0)
			(effects
				(font
					(size 1.27 1.27)
					(thickness 0.15)
				)
				(justify left bottom)
				(hide yes)
			)
		)
		(property "Datasheet" ""
			(at 189.23 69.85 0)
			(effects
				(font
					(size 1.27 1.27)
					(thickness 0.15)
				)
				(justify left bottom)
				(hide yes)
			)
		)
		(property "Description" ""
			(at 198.12 57.15 0)
			(effects
				(font
					(size 1.27 1.27)
				)
				(hide yes)
			)
		)
		(property "Author" "Antmicro"
			(at 189.23 64.77 0)
			(effects
				(font
					(size 1.27 1.27)
					(thickness 0.15)
				)
				(justify left bottom)
				(hide yes)
			)
		)
		(property "License" "Apache-2.0"
			(at 189.23 67.31 0)
			(effects
				(font
					(size 1.27 1.27)
					(thickness 0.15)
				)
				(justify left bottom)
				(hide yes)
			)
		)
		(pin "1"
		)
		(instances
			(project "jetson-agx-thor-baseboard"
				(path ""
					(reference "#PWR0251")
					(unit 1)
				)
			)
		)
	)
	(symbol
		(lib_id "antmicroResistors0402:R_100k_0402")
		(at 97.79 210.82 270)
		(unit 1)
		(exclude_from_sim no)
		(in_bom yes)
		(on_board yes)
		(dnp no)
		(property "Reference" "R272"
			(at 99.06 212.09 90)
			(effects
				(font
					(size 1.27 1.27)
				)
				(justify left)
			)
		)
		(property "Value" "R_100k_0402"
			(at 85.09 231.14 0)
			(effects
				(font
					(size 1.27 1.27)
					(thickness 0.15)
				)
				(justify left bottom)
				(hide yes)
			)
		)
		(property "Footprint" "antmicro-footprints:R_0402_1005Metric"
			(at 82.55 231.14 0)
			(effects
				(font
					(size 1.27 1.27)
					(thickness 0.15)
				)
				(justify left bottom)
				(hide yes)
			)
		)
		(property "Datasheet" "https://www.bourns.com/docs/product-datasheets/cr.pdf"
			(at 80.01 231.14 0)
			(effects
				(font
					(size 1.27 1.27)
					(thickness 0.15)
				)
				(justify left bottom)
				(hide yes)
			)
		)
		(property "Description" "SMD Chip Resistor, 100 kohm, ± 1%, 62.5 mW, 0402 [1005 Metric], Thick Film, General Purpose"
			(at 97.79 210.82 0)
			(effects
				(font
					(size 1.27 1.27)
				)
				(hide yes)
			)
		)
		(property "Manufacturer" "Bourns"
			(at 74.93 231.14 0)
			(effects
				(font
					(size 1.27 1.27)
					(thickness 0.15)
				)
				(justify left bottom)
				(hide yes)
			)
		)
		(property "MPN" "CR0402-FX-1003GLF"
			(at 77.47 231.14 0)
			(effects
				(font
					(size 1.27 1.27)
					(thickness 0.15)
				)
				(justify left bottom)
				(hide yes)
			)
		)
		(property "Val" "100k"
			(at 99.06 214.63 90)
			(effects
				(font
					(size 1.27 1.27)
					(thickness 0.15)
				)
				(justify left)
			)
		)
		(property "License" "Apache-2.0"
			(at 72.39 231.14 0)
			(effects
				(font
					(size 1.27 1.27)
					(thickness 0.15)
				)
				(justify left bottom)
				(hide yes)
			)
		)
		(property "Author" "Antmicro"
			(at 69.85 231.14 0)
			(effects
				(font
					(size 1.27 1.27)
					(thickness 0.15)
				)
				(justify left bottom)
				(hide yes)
			)
		)
		(property "Tolerance" "1%"
			(at 87.63 231.14 0)
			(effects
				(font
					(size 1.27 1.27)
				)
				(justify left bottom)
				(hide yes)
			)
		)
		(pin "1"
		)
		(pin "2"
		)
		(instances
			(project "jetson-agx-thor-baseboard"
				(path ""
					(reference "R272")
					(unit 1)
				)
			)
		)
	)
	(symbol
		(lib_id "antmicropower:GND")
		(at 83.82 110.49 0)
		(mirror y)
		(unit 1)
		(exclude_from_sim no)
		(in_bom yes)
		(on_board yes)
		(dnp no)
		(fields_autoplaced yes)
		(property "Reference" "#PWR0236"
			(at 83.82 116.84 0)
			(effects
				(font
					(size 1.27 1.27)
				)
				(justify left bottom)
				(hide yes)
			)
		)
		(property "Value" "GND"
			(at 83.82 114.3 0)
			(effects
				(font
					(size 1.27 1.27)
					(thickness 0.15)
				)
			)
		)
		(property "Footprint" ""
			(at 74.93 118.11 0)
			(effects
				(font
					(size 1.27 1.27)
					(thickness 0.15)
				)
				(justify left bottom)
				(hide yes)
			)
		)
		(property "Datasheet" ""
			(at 74.93 123.19 0)
			(effects
				(font
					(size 1.27 1.27)
					(thickness 0.15)
				)
				(justify left bottom)
				(hide yes)
			)
		)
		(property "Description" ""
			(at 83.82 110.49 0)
			(effects
				(font
					(size 1.27 1.27)
				)
				(hide yes)
			)
		)
		(property "Author" "Antmicro"
			(at 74.93 118.11 0)
			(effects
				(font
					(size 1.27 1.27)
					(thickness 0.15)
				)
				(justify left bottom)
				(hide yes)
			)
		)
		(property "License" "Apache-2.0"
			(at 74.93 120.65 0)
			(effects
				(font
					(size 1.27 1.27)
					(thickness 0.15)
				)
				(justify left bottom)
				(hide yes)
			)
		)
		(pin "1"
		)
		(instances
			(project "jetson-agx-thor-baseboard"
				(path ""
					(reference "#PWR0236")
					(unit 1)
				)
			)
		)
	)
)
